FILE_TYPE = MACRO_DRAWING;
SET COLOR_WIRE YELLOW;
SET COLOR_PROP ORANGE;
SET COLOR_DOT WHITE;
SET COLOR_ARC YELLOW;
SET COLOR_BODY GREEN;
SET COLOR_NOTE PURPLE;
SET PROP_DISPLAY VALUE;
SET PAGE_NUMBER P93;
FORCEADD OFFPAGE..5
(-8300 2000);
FORCEPROP 2 LAST $XR0 18 
J 0
(-8554 2000);
DISPLAY 0.638298 (-8554 2000);
PAINT MONO (-8554 2000);
FORCEPROP 2 LAST CDS_LIB mstr_standard
J 0
(-8300 2000);
DISPLAY 0.808511 (-8300 2000);
DISPLAY INVISIBLE (-8300 2000);
FORCEPROP 1 LAST OFFPAGE TRUE
J 0
(-7975 1875);
DISPLAY 0.872340 (-7975 1875);
PAINT GREEN (-7975 1875);
DISPLAY INVISIBLE (-7975 1875);
FORCEPROP 1 LAST COMMENT_BODY TRUE
J 0
(-8200 1925);
DISPLAY 0.872340 (-8200 1925);
PAINT GREEN (-8200 1925);
DISPLAY INVISIBLE (-8200 1925);
FORCEPROP 2 LAST PATH I1
J 0
(-8250 2075);
DISPLAY 1.021277 (-8250 2075);
DISPLAY INVISIBLE (-8250 2075);
FORCEADD OFFPAGE..6
(-8300 3650);
FORCEPROP 2 LAST $XR0 18 
J 0
(-8549 3650);
DISPLAY 0.638298 (-8549 3650);
PAINT MONO (-8549 3650);
FORCEPROP 2 LAST CDS_LIB mstr_standard
J 0
(-8300 3650);
DISPLAY 0.723404 (-8300 3650);
PAINT MONO (-8300 3650);
DISPLAY INVISIBLE (-8300 3650);
FORCEPROP 1 LAST OFFPAGE TRUE
J 0
(-7975 3525);
DISPLAY 0.872340 (-7975 3525);
PAINT GREEN (-7975 3525);
DISPLAY INVISIBLE (-7975 3525);
FORCEPROP 1 LAST COMMENT_BODY TRUE
J 0
(-8200 3575);
DISPLAY 0.872340 (-8200 3575);
PAINT GREEN (-8200 3575);
DISPLAY INVISIBLE (-8200 3575);
FORCEPROP 2 LAST PATH I10
J 0
(-8250 3725);
DISPLAY 1.021277 (-8250 3725);
DISPLAY INVISIBLE (-8250 3725);
FORCEADD TAP..1
(-6000 4250);
FORCEPROP 3 LASTPIN (-6050 4250) SIG_NAME M_I_CPU0_SA_DQ<7>
J 0
(-6040 4260);
DISPLAY 0.659574 (-6040 4260);
PAINT MONO (-6040 4260);
DISPLAY INVISIBLE (-6040 4260);
FORCEPROP 1 LASTPIN (-6050 4250) BN 7
J 0
(-6062 4258);
DISPLAY 0.489362 (-6062 4258);
PAINT GREEN (-6062 4258);
FORCEPROP 2 LAST CDS_LIB mstr_standard
J 0
(-6000 4250);
DISPLAY 0.723404 (-6000 4250);
PAINT MONO (-6000 4250);
DISPLAY INVISIBLE (-6000 4250);
FORCEPROP 1 LAST BODY_TYPE PLUMBING
J 0
(-6000 4300);
DISPLAY 0.872340 (-6000 4300);
PAINT GREEN (-6000 4300);
DISPLAY INVISIBLE (-6000 4300);
FORCEPROP 1 LAST HDL_TAP TRUE
J 0
(-5675 4125);
DISPLAY 0.872340 (-5675 4125);
DISPLAY INVISIBLE (-5675 4125);
FORCEPROP 1 LAST PATH I100
J 0
(-6002 4250);
DISPLAY 0.872340 (-6002 4250);
PAINT GREEN (-6002 4250);
DISPLAY INVISIBLE (-6002 4250);
FORCEADD TAP..1
(-6000 4300);
FORCEPROP 3 LASTPIN (-6050 4300) SIG_NAME M_I_CPU0_SA_DQ<8>
J 0
(-6040 4310);
DISPLAY 0.659574 (-6040 4310);
PAINT MONO (-6040 4310);
DISPLAY INVISIBLE (-6040 4310);
FORCEPROP 1 LASTPIN (-6050 4300) BN 8
J 0
(-6062 4308);
DISPLAY 0.489362 (-6062 4308);
PAINT GREEN (-6062 4308);
FORCEPROP 2 LAST CDS_LIB mstr_standard
J 0
(-6000 4300);
DISPLAY 0.723404 (-6000 4300);
PAINT MONO (-6000 4300);
DISPLAY INVISIBLE (-6000 4300);
FORCEPROP 1 LAST BODY_TYPE PLUMBING
J 0
(-6000 4350);
DISPLAY 0.872340 (-6000 4350);
PAINT GREEN (-6000 4350);
DISPLAY INVISIBLE (-6000 4350);
FORCEPROP 1 LAST HDL_TAP TRUE
J 0
(-5675 4175);
DISPLAY 0.872340 (-5675 4175);
DISPLAY INVISIBLE (-5675 4175);
FORCEPROP 1 LAST PATH I101
J 0
(-6002 4300);
DISPLAY 0.872340 (-6002 4300);
PAINT GREEN (-6002 4300);
DISPLAY INVISIBLE (-6002 4300);
FORCEADD TAP..1
(-6000 4350);
FORCEPROP 3 LASTPIN (-6050 4350) SIG_NAME M_I_CPU0_SA_DQ<9>
J 0
(-6040 4360);
DISPLAY 0.659574 (-6040 4360);
PAINT MONO (-6040 4360);
DISPLAY INVISIBLE (-6040 4360);
FORCEPROP 1 LASTPIN (-6050 4350) BN 9
J 0
(-6062 4358);
DISPLAY 0.489362 (-6062 4358);
PAINT GREEN (-6062 4358);
FORCEPROP 2 LAST CDS_LIB mstr_standard
J 0
(-6000 4350);
DISPLAY 0.723404 (-6000 4350);
PAINT MONO (-6000 4350);
DISPLAY INVISIBLE (-6000 4350);
FORCEPROP 1 LAST BODY_TYPE PLUMBING
J 0
(-6000 4400);
DISPLAY 0.872340 (-6000 4400);
PAINT GREEN (-6000 4400);
DISPLAY INVISIBLE (-6000 4400);
FORCEPROP 1 LAST HDL_TAP TRUE
J 0
(-5675 4225);
DISPLAY 0.872340 (-5675 4225);
DISPLAY INVISIBLE (-5675 4225);
FORCEPROP 1 LAST PATH I102
J 0
(-6002 4350);
DISPLAY 0.872340 (-6002 4350);
PAINT GREEN (-6002 4350);
DISPLAY INVISIBLE (-6002 4350);
FORCEADD TAP..1
(-6000 4450);
FORCEPROP 3 LASTPIN (-6050 4450) SIG_NAME M_I_CPU0_SA_DQ<11>
J 0
(-6040 4460);
DISPLAY 0.659574 (-6040 4460);
PAINT MONO (-6040 4460);
DISPLAY INVISIBLE (-6040 4460);
FORCEPROP 1 LASTPIN (-6050 4450) BN 11
J 0
(-6062 4458);
DISPLAY 0.489362 (-6062 4458);
PAINT GREEN (-6062 4458);
FORCEPROP 2 LAST CDS_LIB mstr_standard
J 0
(-6000 4450);
DISPLAY 0.723404 (-6000 4450);
PAINT MONO (-6000 4450);
DISPLAY INVISIBLE (-6000 4450);
FORCEPROP 1 LAST BODY_TYPE PLUMBING
J 0
(-6000 4500);
DISPLAY 0.872340 (-6000 4500);
PAINT GREEN (-6000 4500);
DISPLAY INVISIBLE (-6000 4500);
FORCEPROP 1 LAST HDL_TAP TRUE
J 0
(-5675 4325);
DISPLAY 0.872340 (-5675 4325);
DISPLAY INVISIBLE (-5675 4325);
FORCEPROP 1 LAST PATH I103
J 0
(-6002 4450);
DISPLAY 0.872340 (-6002 4450);
PAINT GREEN (-6002 4450);
DISPLAY INVISIBLE (-6002 4450);
FORCEADD TAP..1
(-6000 4400);
FORCEPROP 3 LASTPIN (-6050 4400) SIG_NAME M_I_CPU0_SA_DQ<10>
J 0
(-6040 4410);
DISPLAY 0.659574 (-6040 4410);
PAINT MONO (-6040 4410);
DISPLAY INVISIBLE (-6040 4410);
FORCEPROP 1 LASTPIN (-6050 4400) BN 10
J 0
(-6062 4408);
DISPLAY 0.489362 (-6062 4408);
PAINT GREEN (-6062 4408);
FORCEPROP 2 LAST CDS_LIB mstr_standard
J 0
(-6000 4400);
DISPLAY 0.723404 (-6000 4400);
PAINT MONO (-6000 4400);
DISPLAY INVISIBLE (-6000 4400);
FORCEPROP 1 LAST BODY_TYPE PLUMBING
J 0
(-6000 4450);
DISPLAY 0.872340 (-6000 4450);
PAINT GREEN (-6000 4450);
DISPLAY INVISIBLE (-6000 4450);
FORCEPROP 1 LAST HDL_TAP TRUE
J 0
(-5675 4275);
DISPLAY 0.872340 (-5675 4275);
DISPLAY INVISIBLE (-5675 4275);
FORCEPROP 1 LAST PATH I104
J 0
(-6002 4400);
DISPLAY 0.872340 (-6002 4400);
PAINT GREEN (-6002 4400);
DISPLAY INVISIBLE (-6002 4400);
FORCEADD TAP..1
(-6000 4500);
FORCEPROP 3 LASTPIN (-6050 4500) SIG_NAME M_I_CPU0_SA_DQ<12>
J 0
(-6040 4510);
DISPLAY 0.659574 (-6040 4510);
PAINT MONO (-6040 4510);
DISPLAY INVISIBLE (-6040 4510);
FORCEPROP 1 LASTPIN (-6050 4500) BN 12
J 0
(-6062 4508);
DISPLAY 0.489362 (-6062 4508);
PAINT GREEN (-6062 4508);
FORCEPROP 2 LAST CDS_LIB mstr_standard
J 0
(-6000 4500);
DISPLAY 0.723404 (-6000 4500);
PAINT MONO (-6000 4500);
DISPLAY INVISIBLE (-6000 4500);
FORCEPROP 1 LAST BODY_TYPE PLUMBING
J 0
(-6000 4550);
DISPLAY 0.872340 (-6000 4550);
PAINT GREEN (-6000 4550);
DISPLAY INVISIBLE (-6000 4550);
FORCEPROP 1 LAST HDL_TAP TRUE
J 0
(-5675 4375);
DISPLAY 0.872340 (-5675 4375);
DISPLAY INVISIBLE (-5675 4375);
FORCEPROP 1 LAST PATH I105
J 0
(-6002 4500);
DISPLAY 0.872340 (-6002 4500);
PAINT GREEN (-6002 4500);
DISPLAY INVISIBLE (-6002 4500);
FORCEADD TAP..1
(-6000 4550);
FORCEPROP 3 LASTPIN (-6050 4550) SIG_NAME M_I_CPU0_SA_DQ<13>
J 0
(-6040 4560);
DISPLAY 0.659574 (-6040 4560);
PAINT MONO (-6040 4560);
DISPLAY INVISIBLE (-6040 4560);
FORCEPROP 1 LASTPIN (-6050 4550) BN 13
J 0
(-6062 4558);
DISPLAY 0.489362 (-6062 4558);
PAINT GREEN (-6062 4558);
FORCEPROP 2 LAST CDS_LIB mstr_standard
J 0
(-6000 4550);
DISPLAY 0.723404 (-6000 4550);
PAINT MONO (-6000 4550);
DISPLAY INVISIBLE (-6000 4550);
FORCEPROP 1 LAST BODY_TYPE PLUMBING
J 0
(-6000 4600);
DISPLAY 0.872340 (-6000 4600);
PAINT GREEN (-6000 4600);
DISPLAY INVISIBLE (-6000 4600);
FORCEPROP 1 LAST HDL_TAP TRUE
J 0
(-5675 4425);
DISPLAY 0.872340 (-5675 4425);
DISPLAY INVISIBLE (-5675 4425);
FORCEPROP 1 LAST PATH I106
J 0
(-6002 4550);
DISPLAY 0.872340 (-6002 4550);
PAINT GREEN (-6002 4550);
DISPLAY INVISIBLE (-6002 4550);
FORCEADD TAP..1
(-6000 4600);
FORCEPROP 3 LASTPIN (-6050 4600) SIG_NAME M_I_CPU0_SA_DQ<14>
J 0
(-6040 4610);
DISPLAY 0.659574 (-6040 4610);
PAINT MONO (-6040 4610);
DISPLAY INVISIBLE (-6040 4610);
FORCEPROP 1 LASTPIN (-6050 4600) BN 14
J 0
(-6062 4608);
DISPLAY 0.489362 (-6062 4608);
PAINT GREEN (-6062 4608);
FORCEPROP 2 LAST CDS_LIB mstr_standard
J 0
(-6000 4600);
DISPLAY 0.723404 (-6000 4600);
PAINT MONO (-6000 4600);
DISPLAY INVISIBLE (-6000 4600);
FORCEPROP 1 LAST BODY_TYPE PLUMBING
J 0
(-6000 4650);
DISPLAY 0.872340 (-6000 4650);
PAINT GREEN (-6000 4650);
DISPLAY INVISIBLE (-6000 4650);
FORCEPROP 1 LAST HDL_TAP TRUE
J 0
(-5675 4475);
DISPLAY 0.872340 (-5675 4475);
DISPLAY INVISIBLE (-5675 4475);
FORCEPROP 1 LAST PATH I107
J 0
(-6002 4600);
DISPLAY 0.872340 (-6002 4600);
PAINT GREEN (-6002 4600);
DISPLAY INVISIBLE (-6002 4600);
FORCEADD TAP..1
(-6000 4700);
FORCEPROP 3 LASTPIN (-6050 4700) SIG_NAME M_I_CPU0_SA_DQ<16>
J 0
(-6040 4710);
DISPLAY 0.659574 (-6040 4710);
PAINT MONO (-6040 4710);
DISPLAY INVISIBLE (-6040 4710);
FORCEPROP 1 LASTPIN (-6050 4700) BN 16
J 0
(-6062 4708);
DISPLAY 0.489362 (-6062 4708);
PAINT GREEN (-6062 4708);
FORCEPROP 2 LAST CDS_LIB mstr_standard
J 0
(-6000 4700);
DISPLAY 0.723404 (-6000 4700);
PAINT MONO (-6000 4700);
DISPLAY INVISIBLE (-6000 4700);
FORCEPROP 1 LAST BODY_TYPE PLUMBING
J 0
(-6000 4750);
DISPLAY 0.872340 (-6000 4750);
PAINT GREEN (-6000 4750);
DISPLAY INVISIBLE (-6000 4750);
FORCEPROP 1 LAST HDL_TAP TRUE
J 0
(-5675 4575);
DISPLAY 0.872340 (-5675 4575);
DISPLAY INVISIBLE (-5675 4575);
FORCEPROP 1 LAST PATH I108
J 0
(-6002 4700);
DISPLAY 0.872340 (-6002 4700);
PAINT GREEN (-6002 4700);
DISPLAY INVISIBLE (-6002 4700);
FORCEADD TAP..1
(-6000 4650);
FORCEPROP 3 LASTPIN (-6050 4650) SIG_NAME M_I_CPU0_SA_DQ<15>
J 0
(-6040 4660);
DISPLAY 0.659574 (-6040 4660);
PAINT MONO (-6040 4660);
DISPLAY INVISIBLE (-6040 4660);
FORCEPROP 1 LASTPIN (-6050 4650) BN 15
J 0
(-6062 4658);
DISPLAY 0.489362 (-6062 4658);
PAINT GREEN (-6062 4658);
FORCEPROP 2 LAST CDS_LIB mstr_standard
J 0
(-6000 4650);
DISPLAY 0.723404 (-6000 4650);
PAINT MONO (-6000 4650);
DISPLAY INVISIBLE (-6000 4650);
FORCEPROP 1 LAST BODY_TYPE PLUMBING
J 0
(-6000 4700);
DISPLAY 0.872340 (-6000 4700);
PAINT GREEN (-6000 4700);
DISPLAY INVISIBLE (-6000 4700);
FORCEPROP 1 LAST HDL_TAP TRUE
J 0
(-5675 4525);
DISPLAY 0.872340 (-5675 4525);
DISPLAY INVISIBLE (-5675 4525);
FORCEPROP 1 LAST PATH I109
J 0
(-6002 4650);
DISPLAY 0.872340 (-6002 4650);
PAINT GREEN (-6002 4650);
DISPLAY INVISIBLE (-6002 4650);
FORCEADD OFFPAGE..1
(-8300 4150);
FORCEPROP 2 LAST $XR0 18 
J 0
(-8521 4150);
DISPLAY 0.638298 (-8521 4150);
PAINT MONO (-8521 4150);
FORCEPROP 2 LAST CDS_LIB mstr_standard
J 0
(-8300 4150);
DISPLAY 0.808511 (-8300 4150);
DISPLAY INVISIBLE (-8300 4150);
FORCEPROP 1 LAST OFFPAGE TRUE
J 0
(-7975 4025);
DISPLAY 0.872340 (-7975 4025);
PAINT GREEN (-7975 4025);
DISPLAY INVISIBLE (-7975 4025);
FORCEPROP 1 LAST COMMENT_BODY TRUE
J 0
(-8175 4050);
DISPLAY 0.872340 (-8175 4050);
PAINT GREEN (-8175 4050);
DISPLAY INVISIBLE (-8175 4050);
FORCEPROP 2 LAST PATH I11
J 0
(-8250 4225);
DISPLAY 1.021277 (-8250 4225);
DISPLAY INVISIBLE (-8250 4225);
FORCEADD TAP..1
(-6000 4800);
FORCEPROP 3 LASTPIN (-6050 4800) SIG_NAME M_I_CPU0_SA_DQ<18>
J 0
(-6040 4810);
DISPLAY 0.659574 (-6040 4810);
PAINT MONO (-6040 4810);
DISPLAY INVISIBLE (-6040 4810);
FORCEPROP 1 LASTPIN (-6050 4800) BN 18
J 0
(-6062 4808);
DISPLAY 0.489362 (-6062 4808);
PAINT GREEN (-6062 4808);
FORCEPROP 2 LAST CDS_LIB mstr_standard
J 0
(-6000 4800);
DISPLAY 0.723404 (-6000 4800);
PAINT MONO (-6000 4800);
DISPLAY INVISIBLE (-6000 4800);
FORCEPROP 1 LAST BODY_TYPE PLUMBING
J 0
(-6000 4850);
DISPLAY 0.872340 (-6000 4850);
PAINT GREEN (-6000 4850);
DISPLAY INVISIBLE (-6000 4850);
FORCEPROP 1 LAST HDL_TAP TRUE
J 0
(-5675 4675);
DISPLAY 0.872340 (-5675 4675);
DISPLAY INVISIBLE (-5675 4675);
FORCEPROP 1 LAST PATH I110
J 0
(-6002 4800);
DISPLAY 0.872340 (-6002 4800);
PAINT GREEN (-6002 4800);
DISPLAY INVISIBLE (-6002 4800);
FORCEADD TAP..1
(-6000 4750);
FORCEPROP 3 LASTPIN (-6050 4750) SIG_NAME M_I_CPU0_SA_DQ<17>
J 0
(-6040 4760);
DISPLAY 0.659574 (-6040 4760);
PAINT MONO (-6040 4760);
DISPLAY INVISIBLE (-6040 4760);
FORCEPROP 1 LASTPIN (-6050 4750) BN 17
J 0
(-6062 4758);
DISPLAY 0.489362 (-6062 4758);
PAINT GREEN (-6062 4758);
FORCEPROP 2 LAST CDS_LIB mstr_standard
J 0
(-6000 4750);
DISPLAY 0.723404 (-6000 4750);
PAINT MONO (-6000 4750);
DISPLAY INVISIBLE (-6000 4750);
FORCEPROP 1 LAST BODY_TYPE PLUMBING
J 0
(-6000 4800);
DISPLAY 0.872340 (-6000 4800);
PAINT GREEN (-6000 4800);
DISPLAY INVISIBLE (-6000 4800);
FORCEPROP 1 LAST HDL_TAP TRUE
J 0
(-5675 4625);
DISPLAY 0.872340 (-5675 4625);
DISPLAY INVISIBLE (-5675 4625);
FORCEPROP 1 LAST PATH I111
J 0
(-6002 4750);
DISPLAY 0.872340 (-6002 4750);
PAINT GREEN (-6002 4750);
DISPLAY INVISIBLE (-6002 4750);
FORCEADD TAP..1
(-6000 4850);
FORCEPROP 3 LASTPIN (-6050 4850) SIG_NAME M_I_CPU0_SA_DQ<19>
J 0
(-6040 4860);
DISPLAY 0.659574 (-6040 4860);
PAINT MONO (-6040 4860);
DISPLAY INVISIBLE (-6040 4860);
FORCEPROP 1 LASTPIN (-6050 4850) BN 19
J 0
(-6062 4858);
DISPLAY 0.489362 (-6062 4858);
PAINT GREEN (-6062 4858);
FORCEPROP 2 LAST CDS_LIB mstr_standard
J 0
(-6000 4850);
DISPLAY 0.723404 (-6000 4850);
PAINT MONO (-6000 4850);
DISPLAY INVISIBLE (-6000 4850);
FORCEPROP 1 LAST BODY_TYPE PLUMBING
J 0
(-6000 4900);
DISPLAY 0.872340 (-6000 4900);
PAINT GREEN (-6000 4900);
DISPLAY INVISIBLE (-6000 4900);
FORCEPROP 1 LAST HDL_TAP TRUE
J 0
(-5675 4725);
DISPLAY 0.872340 (-5675 4725);
DISPLAY INVISIBLE (-5675 4725);
FORCEPROP 1 LAST PATH I112
J 0
(-6002 4850);
DISPLAY 0.872340 (-6002 4850);
PAINT GREEN (-6002 4850);
DISPLAY INVISIBLE (-6002 4850);
FORCEADD TAP..1
(-6000 4950);
FORCEPROP 3 LASTPIN (-6050 4950) SIG_NAME M_I_CPU0_SA_DQ<21>
J 0
(-6040 4960);
DISPLAY 0.659574 (-6040 4960);
PAINT MONO (-6040 4960);
DISPLAY INVISIBLE (-6040 4960);
FORCEPROP 1 LASTPIN (-6050 4950) BN 21
J 0
(-6062 4958);
DISPLAY 0.489362 (-6062 4958);
PAINT GREEN (-6062 4958);
FORCEPROP 2 LAST CDS_LIB mstr_standard
J 0
(-6000 4950);
DISPLAY 0.723404 (-6000 4950);
PAINT MONO (-6000 4950);
DISPLAY INVISIBLE (-6000 4950);
FORCEPROP 1 LAST BODY_TYPE PLUMBING
J 0
(-6000 5000);
DISPLAY 0.872340 (-6000 5000);
PAINT GREEN (-6000 5000);
DISPLAY INVISIBLE (-6000 5000);
FORCEPROP 1 LAST HDL_TAP TRUE
J 0
(-5675 4825);
DISPLAY 0.872340 (-5675 4825);
DISPLAY INVISIBLE (-5675 4825);
FORCEPROP 1 LAST PATH I113
J 0
(-6002 4950);
DISPLAY 0.872340 (-6002 4950);
PAINT GREEN (-6002 4950);
DISPLAY INVISIBLE (-6002 4950);
FORCEADD TAP..1
(-6000 4900);
FORCEPROP 3 LASTPIN (-6050 4900) SIG_NAME M_I_CPU0_SA_DQ<20>
J 0
(-6040 4910);
DISPLAY 0.659574 (-6040 4910);
PAINT MONO (-6040 4910);
DISPLAY INVISIBLE (-6040 4910);
FORCEPROP 1 LASTPIN (-6050 4900) BN 20
J 0
(-6062 4908);
DISPLAY 0.489362 (-6062 4908);
PAINT GREEN (-6062 4908);
FORCEPROP 2 LAST CDS_LIB mstr_standard
J 0
(-6000 4900);
DISPLAY 0.723404 (-6000 4900);
PAINT MONO (-6000 4900);
DISPLAY INVISIBLE (-6000 4900);
FORCEPROP 1 LAST BODY_TYPE PLUMBING
J 0
(-6000 4950);
DISPLAY 0.872340 (-6000 4950);
PAINT GREEN (-6000 4950);
DISPLAY INVISIBLE (-6000 4950);
FORCEPROP 1 LAST HDL_TAP TRUE
J 0
(-5675 4775);
DISPLAY 0.872340 (-5675 4775);
DISPLAY INVISIBLE (-5675 4775);
FORCEPROP 1 LAST PATH I114
J 0
(-6002 4900);
DISPLAY 0.872340 (-6002 4900);
PAINT GREEN (-6002 4900);
DISPLAY INVISIBLE (-6002 4900);
FORCEADD TAP..1
(-6000 5000);
FORCEPROP 3 LASTPIN (-6050 5000) SIG_NAME M_I_CPU0_SA_DQ<22>
J 0
(-6040 5010);
DISPLAY 0.659574 (-6040 5010);
PAINT MONO (-6040 5010);
DISPLAY INVISIBLE (-6040 5010);
FORCEPROP 1 LASTPIN (-6050 5000) BN 22
J 0
(-6062 5008);
DISPLAY 0.489362 (-6062 5008);
PAINT GREEN (-6062 5008);
FORCEPROP 2 LAST CDS_LIB mstr_standard
J 0
(-6000 5000);
DISPLAY 0.723404 (-6000 5000);
PAINT MONO (-6000 5000);
DISPLAY INVISIBLE (-6000 5000);
FORCEPROP 1 LAST BODY_TYPE PLUMBING
J 0
(-6000 5050);
DISPLAY 0.872340 (-6000 5050);
PAINT GREEN (-6000 5050);
DISPLAY INVISIBLE (-6000 5050);
FORCEPROP 1 LAST HDL_TAP TRUE
J 0
(-5675 4875);
DISPLAY 0.872340 (-5675 4875);
DISPLAY INVISIBLE (-5675 4875);
FORCEPROP 1 LAST PATH I115
J 0
(-6002 5000);
DISPLAY 0.872340 (-6002 5000);
PAINT GREEN (-6002 5000);
DISPLAY INVISIBLE (-6002 5000);
FORCEADD TAP..1
(-6000 5050);
FORCEPROP 3 LASTPIN (-6050 5050) SIG_NAME M_I_CPU0_SA_DQ<23>
J 0
(-6040 5060);
DISPLAY 0.659574 (-6040 5060);
PAINT MONO (-6040 5060);
DISPLAY INVISIBLE (-6040 5060);
FORCEPROP 1 LASTPIN (-6050 5050) BN 23
J 0
(-6062 5058);
DISPLAY 0.489362 (-6062 5058);
PAINT GREEN (-6062 5058);
FORCEPROP 2 LAST CDS_LIB mstr_standard
J 0
(-6000 5050);
DISPLAY 0.723404 (-6000 5050);
PAINT MONO (-6000 5050);
DISPLAY INVISIBLE (-6000 5050);
FORCEPROP 1 LAST BODY_TYPE PLUMBING
J 0
(-6000 5100);
DISPLAY 0.872340 (-6000 5100);
PAINT GREEN (-6000 5100);
DISPLAY INVISIBLE (-6000 5100);
FORCEPROP 1 LAST HDL_TAP TRUE
J 0
(-5675 4925);
DISPLAY 0.872340 (-5675 4925);
DISPLAY INVISIBLE (-5675 4925);
FORCEPROP 1 LAST PATH I116
J 0
(-6002 5050);
DISPLAY 0.872340 (-6002 5050);
PAINT GREEN (-6002 5050);
DISPLAY INVISIBLE (-6002 5050);
FORCEADD TAP..1
(-6000 5150);
FORCEPROP 3 LASTPIN (-6050 5150) SIG_NAME M_I_CPU0_SA_DQ<25>
J 0
(-6040 5160);
DISPLAY 0.659574 (-6040 5160);
PAINT MONO (-6040 5160);
DISPLAY INVISIBLE (-6040 5160);
FORCEPROP 1 LASTPIN (-6050 5150) BN 25
J 0
(-6062 5158);
DISPLAY 0.489362 (-6062 5158);
PAINT GREEN (-6062 5158);
FORCEPROP 2 LAST CDS_LIB mstr_standard
J 0
(-6000 5150);
DISPLAY 0.723404 (-6000 5150);
PAINT MONO (-6000 5150);
DISPLAY INVISIBLE (-6000 5150);
FORCEPROP 1 LAST BODY_TYPE PLUMBING
J 0
(-6000 5200);
DISPLAY 0.872340 (-6000 5200);
PAINT GREEN (-6000 5200);
DISPLAY INVISIBLE (-6000 5200);
FORCEPROP 1 LAST HDL_TAP TRUE
J 0
(-5675 5025);
DISPLAY 0.872340 (-5675 5025);
DISPLAY INVISIBLE (-5675 5025);
FORCEPROP 1 LAST PATH I117
J 0
(-6002 5150);
DISPLAY 0.872340 (-6002 5150);
PAINT GREEN (-6002 5150);
DISPLAY INVISIBLE (-6002 5150);
FORCEADD TAP..1
(-6000 5100);
FORCEPROP 3 LASTPIN (-6050 5100) SIG_NAME M_I_CPU0_SA_DQ<24>
J 0
(-6040 5110);
DISPLAY 0.659574 (-6040 5110);
PAINT MONO (-6040 5110);
DISPLAY INVISIBLE (-6040 5110);
FORCEPROP 1 LASTPIN (-6050 5100) BN 24
J 0
(-6062 5108);
DISPLAY 0.489362 (-6062 5108);
PAINT GREEN (-6062 5108);
FORCEPROP 2 LAST CDS_LIB mstr_standard
J 0
(-6000 5100);
DISPLAY 0.723404 (-6000 5100);
PAINT MONO (-6000 5100);
DISPLAY INVISIBLE (-6000 5100);
FORCEPROP 1 LAST BODY_TYPE PLUMBING
J 0
(-6000 5150);
DISPLAY 0.872340 (-6000 5150);
PAINT GREEN (-6000 5150);
DISPLAY INVISIBLE (-6000 5150);
FORCEPROP 1 LAST HDL_TAP TRUE
J 0
(-5675 4975);
DISPLAY 0.872340 (-5675 4975);
DISPLAY INVISIBLE (-5675 4975);
FORCEPROP 1 LAST PATH I118
J 0
(-6002 5100);
DISPLAY 0.872340 (-6002 5100);
PAINT GREEN (-6002 5100);
DISPLAY INVISIBLE (-6002 5100);
FORCEADD TAP..1
(-6000 5200);
FORCEPROP 3 LASTPIN (-6050 5200) SIG_NAME M_I_CPU0_SA_DQ<26>
J 0
(-6040 5210);
DISPLAY 0.659574 (-6040 5210);
PAINT MONO (-6040 5210);
DISPLAY INVISIBLE (-6040 5210);
FORCEPROP 1 LASTPIN (-6050 5200) BN 26
J 0
(-6062 5208);
DISPLAY 0.489362 (-6062 5208);
PAINT GREEN (-6062 5208);
FORCEPROP 2 LAST CDS_LIB mstr_standard
J 0
(-6000 5200);
DISPLAY 0.723404 (-6000 5200);
PAINT MONO (-6000 5200);
DISPLAY INVISIBLE (-6000 5200);
FORCEPROP 1 LAST BODY_TYPE PLUMBING
J 0
(-6000 5250);
DISPLAY 0.872340 (-6000 5250);
PAINT GREEN (-6000 5250);
DISPLAY INVISIBLE (-6000 5250);
FORCEPROP 1 LAST HDL_TAP TRUE
J 0
(-5675 5075);
DISPLAY 0.872340 (-5675 5075);
DISPLAY INVISIBLE (-5675 5075);
FORCEPROP 1 LAST PATH I119
J 0
(-6002 5200);
DISPLAY 0.872340 (-6002 5200);
PAINT GREEN (-6002 5200);
DISPLAY INVISIBLE (-6002 5200);
FORCEADD OFFPAGE..6
(-8300 4100);
FORCEPROP 2 LAST $XR0 18 
J 0
(-8549 4100);
DISPLAY 0.638298 (-8549 4100);
PAINT MONO (-8549 4100);
FORCEPROP 2 LAST CDS_LIB mstr_standard
J 0
(-8300 4100);
DISPLAY 0.723404 (-8300 4100);
PAINT MONO (-8300 4100);
DISPLAY INVISIBLE (-8300 4100);
FORCEPROP 1 LAST OFFPAGE TRUE
J 0
(-7975 3975);
DISPLAY 0.872340 (-7975 3975);
PAINT GREEN (-7975 3975);
DISPLAY INVISIBLE (-7975 3975);
FORCEPROP 1 LAST COMMENT_BODY TRUE
J 0
(-8200 4025);
DISPLAY 0.872340 (-8200 4025);
PAINT GREEN (-8200 4025);
DISPLAY INVISIBLE (-8200 4025);
FORCEPROP 2 LAST PATH I12
J 0
(-8250 4175);
DISPLAY 1.021277 (-8250 4175);
DISPLAY INVISIBLE (-8250 4175);
FORCEADD TAP..1
(-6000 5350);
FORCEPROP 3 LASTPIN (-6050 5350) SIG_NAME M_I_CPU0_SA_DQ<29>
J 0
(-6040 5360);
DISPLAY 0.659574 (-6040 5360);
PAINT MONO (-6040 5360);
DISPLAY INVISIBLE (-6040 5360);
FORCEPROP 1 LASTPIN (-6050 5350) BN 29
J 0
(-6062 5358);
DISPLAY 0.489362 (-6062 5358);
PAINT GREEN (-6062 5358);
FORCEPROP 2 LAST CDS_LIB mstr_standard
J 0
(-6000 5350);
DISPLAY 0.723404 (-6000 5350);
PAINT MONO (-6000 5350);
DISPLAY INVISIBLE (-6000 5350);
FORCEPROP 1 LAST BODY_TYPE PLUMBING
J 0
(-6000 5400);
DISPLAY 0.872340 (-6000 5400);
PAINT GREEN (-6000 5400);
DISPLAY INVISIBLE (-6000 5400);
FORCEPROP 1 LAST HDL_TAP TRUE
J 0
(-5675 5225);
DISPLAY 0.872340 (-5675 5225);
DISPLAY INVISIBLE (-5675 5225);
FORCEPROP 1 LAST PATH I120
J 0
(-6002 5350);
DISPLAY 0.872340 (-6002 5350);
PAINT GREEN (-6002 5350);
DISPLAY INVISIBLE (-6002 5350);
FORCEADD TAP..1
(-6000 5300);
FORCEPROP 3 LASTPIN (-6050 5300) SIG_NAME M_I_CPU0_SA_DQ<28>
J 0
(-6040 5310);
DISPLAY 0.659574 (-6040 5310);
PAINT MONO (-6040 5310);
DISPLAY INVISIBLE (-6040 5310);
FORCEPROP 1 LASTPIN (-6050 5300) BN 28
J 0
(-6062 5308);
DISPLAY 0.489362 (-6062 5308);
PAINT GREEN (-6062 5308);
FORCEPROP 2 LAST CDS_LIB mstr_standard
J 0
(-6000 5300);
DISPLAY 0.723404 (-6000 5300);
PAINT MONO (-6000 5300);
DISPLAY INVISIBLE (-6000 5300);
FORCEPROP 1 LAST BODY_TYPE PLUMBING
J 0
(-6000 5350);
DISPLAY 0.872340 (-6000 5350);
PAINT GREEN (-6000 5350);
DISPLAY INVISIBLE (-6000 5350);
FORCEPROP 1 LAST HDL_TAP TRUE
J 0
(-5675 5175);
DISPLAY 0.872340 (-5675 5175);
DISPLAY INVISIBLE (-5675 5175);
FORCEPROP 1 LAST PATH I121
J 0
(-6002 5300);
DISPLAY 0.872340 (-6002 5300);
PAINT GREEN (-6002 5300);
DISPLAY INVISIBLE (-6002 5300);
FORCEADD TAP..1
(-6000 5250);
FORCEPROP 3 LASTPIN (-6050 5250) SIG_NAME M_I_CPU0_SA_DQ<27>
J 0
(-6040 5260);
DISPLAY 0.659574 (-6040 5260);
PAINT MONO (-6040 5260);
DISPLAY INVISIBLE (-6040 5260);
FORCEPROP 1 LASTPIN (-6050 5250) BN 27
J 0
(-6062 5258);
DISPLAY 0.489362 (-6062 5258);
PAINT GREEN (-6062 5258);
FORCEPROP 2 LAST CDS_LIB mstr_standard
J 0
(-6000 5250);
DISPLAY 0.723404 (-6000 5250);
PAINT MONO (-6000 5250);
DISPLAY INVISIBLE (-6000 5250);
FORCEPROP 1 LAST BODY_TYPE PLUMBING
J 0
(-6000 5300);
DISPLAY 0.872340 (-6000 5300);
PAINT GREEN (-6000 5300);
DISPLAY INVISIBLE (-6000 5300);
FORCEPROP 1 LAST HDL_TAP TRUE
J 0
(-5675 5125);
DISPLAY 0.872340 (-5675 5125);
DISPLAY INVISIBLE (-5675 5125);
FORCEPROP 1 LAST PATH I122
J 0
(-6002 5250);
DISPLAY 0.872340 (-6002 5250);
PAINT GREEN (-6002 5250);
DISPLAY INVISIBLE (-6002 5250);
FORCEADD TAP..1
(-6000 5400);
FORCEPROP 3 LASTPIN (-6050 5400) SIG_NAME M_I_CPU0_SA_DQ<30>
J 0
(-6040 5410);
DISPLAY 0.659574 (-6040 5410);
PAINT MONO (-6040 5410);
DISPLAY INVISIBLE (-6040 5410);
FORCEPROP 1 LASTPIN (-6050 5400) BN 30
J 0
(-6062 5408);
DISPLAY 0.489362 (-6062 5408);
PAINT GREEN (-6062 5408);
FORCEPROP 2 LAST CDS_LIB mstr_standard
J 0
(-6000 5400);
DISPLAY 0.723404 (-6000 5400);
PAINT MONO (-6000 5400);
DISPLAY INVISIBLE (-6000 5400);
FORCEPROP 1 LAST BODY_TYPE PLUMBING
J 0
(-6000 5450);
DISPLAY 0.872340 (-6000 5450);
PAINT GREEN (-6000 5450);
DISPLAY INVISIBLE (-6000 5450);
FORCEPROP 1 LAST HDL_TAP TRUE
J 0
(-5675 5275);
DISPLAY 0.872340 (-5675 5275);
DISPLAY INVISIBLE (-5675 5275);
FORCEPROP 1 LAST PATH I123
J 0
(-6002 5400);
DISPLAY 0.872340 (-6002 5400);
PAINT GREEN (-6002 5400);
DISPLAY INVISIBLE (-6002 5400);
FORCEADD TAP..1
(-6000 5450);
FORCEPROP 3 LASTPIN (-6050 5450) SIG_NAME M_I_CPU0_SA_DQ<31>
J 0
(-6040 5460);
DISPLAY 0.659574 (-6040 5460);
PAINT MONO (-6040 5460);
DISPLAY INVISIBLE (-6040 5460);
FORCEPROP 1 LASTPIN (-6050 5450) BN 31
J 0
(-6062 5458);
DISPLAY 0.489362 (-6062 5458);
PAINT GREEN (-6062 5458);
FORCEPROP 2 LAST CDS_LIB mstr_standard
J 0
(-6000 5450);
DISPLAY 0.723404 (-6000 5450);
PAINT MONO (-6000 5450);
DISPLAY INVISIBLE (-6000 5450);
FORCEPROP 1 LAST BODY_TYPE PLUMBING
J 0
(-6000 5500);
DISPLAY 0.872340 (-6000 5500);
PAINT GREEN (-6000 5500);
DISPLAY INVISIBLE (-6000 5500);
FORCEPROP 1 LAST HDL_TAP TRUE
J 0
(-5675 5325);
DISPLAY 0.872340 (-5675 5325);
DISPLAY INVISIBLE (-5675 5325);
FORCEPROP 1 LAST PATH I124
J 0
(-6002 5450);
DISPLAY 0.872340 (-6002 5450);
PAINT GREEN (-6002 5450);
DISPLAY INVISIBLE (-6002 5450);
FORCEADD OFFPAGE..3
(-5325 5475);
FORCEPROP 2 LAST $XR0 18 
J 0
(-5111 5475);
DISPLAY 0.638298 (-5111 5475);
PAINT MONO (-5111 5475);
FORCEPROP 2 LAST CDS_LIB mstr_standard
J 0
(-5325 5475);
DISPLAY 0.723404 (-5325 5475);
PAINT MONO (-5325 5475);
DISPLAY INVISIBLE (-5325 5475);
FORCEPROP 1 LAST OFFPAGE TRUE
J 0
(-5000 5350);
DISPLAY 0.872340 (-5000 5350);
PAINT GREEN (-5000 5350);
DISPLAY INVISIBLE (-5000 5350);
FORCEPROP 1 LAST COMMENT_BODY TRUE
J 0
(-5375 5375);
DISPLAY 0.872340 (-5375 5375);
PAINT GREEN (-5375 5375);
DISPLAY INVISIBLE (-5375 5375);
FORCEPROP 2 LAST PATH I125
J 0
(-5125 5550);
DISPLAY 1.021277 (-5125 5550);
DISPLAY INVISIBLE (-5125 5550);
FORCEADD OFFPAGE..5
(-7200 1475);
FORCEPROP 2 LAST $XR0 94 
J 0
(-7424 1475);
DISPLAY 0.638298 (-7424 1475);
PAINT MONO (-7424 1475);
FORCEPROP 2 LAST BOM_COST MEM
J 0
(-7275 1550);
DISPLAY 0.808511 (-7275 1550);
DISPLAY INVISIBLE (-7275 1550);
FORCEPROP 2 LAST CDS_LIB mstr_standard
J 0
(-7200 1475);
DISPLAY 0.808511 (-7200 1475);
DISPLAY INVISIBLE (-7200 1475);
FORCEPROP 1 LAST OFFPAGE TRUE
J 0
(-6875 1350);
DISPLAY 0.872340 (-6875 1350);
PAINT GREEN (-6875 1350);
DISPLAY INVISIBLE (-6875 1350);
FORCEPROP 1 LAST COMMENT_BODY TRUE
J 0
(-7100 1400);
DISPLAY 0.872340 (-7100 1400);
PAINT GREEN (-7100 1400);
DISPLAY INVISIBLE (-7100 1400);
FORCEPROP 2 LAST PATH I126
J 0
(-7450 1525);
DISPLAY 1.021277 (-7450 1525);
DISPLAY INVISIBLE (-7450 1525);
FORCEADD GND..1
(-6425 1150);
FORCEPROP 3 LASTPIN (-6425 1200) SIG_NAME GND\g
J 0
(-6415 1210);
DISPLAY 0.659574 (-6415 1210);
PAINT MONO (-6415 1210);
DISPLAY INVISIBLE (-6415 1210);
FORCEPROP 1 LAST VOLTAGE 0.0
J 0
(-6470 1107);
DISPLAY 0.723404 (-6470 1107);
PAINT SKYBLUE (-6470 1107);
DISPLAY INVISIBLE (-6470 1107);
FORCEPROP 1 LAST SIZE 1B
J 0
(-6350 1100);
DISPLAY 0.851064 (-6350 1100);
PAINT GREEN (-6350 1100);
DISPLAY INVISIBLE (-6350 1100);
FORCEPROP 2 LAST CDS_LIB mstr_symbols
J 0
(-6425 1150);
DISPLAY 0.808511 (-6425 1150);
DISPLAY INVISIBLE (-6425 1150);
FORCEPROP 2 LAST BOM_COST MEM
J 0
(-6525 1225);
DISPLAY 0.808511 (-6525 1225);
DISPLAY INVISIBLE (-6525 1225);
FORCEPROP 1 LAST BODY_TYPE PLUMBING
J 0
(-6470 1107);
DISPLAY 0.340426 (-6470 1107);
PAINT GREEN (-6470 1107);
DISPLAY INVISIBLE (-6470 1107);
FORCEPROP 1 LAST HDL_POWER GND
J 0
(-6425 1300);
DISPLAY 0.851064 (-6425 1300);
PAINT GREEN (-6425 1300);
DISPLAY INVISIBLE (-6425 1300);
FORCEPROP 1 LAST PATH I127
J 0
(-6350 1150);
DISPLAY 0.872340 (-6350 1150);
PAINT AQUA (-6350 1150);
DISPLAY INVISIBLE (-6350 1150);
FORCEADD Q_RES..2
(-6425 1300);
FORCEPROP 1 LAST LOCATION R766
J 0
(-6380 1425);
DISPLAY 0.489362 (-6380 1425);
PAINT SKYBLUE (-6380 1425);
FORCEPROP 0 LAST $SEC 1
J 0
(-6375 1475);
DISPLAY 0.680851 (-6375 1475);
PAINT MONO (-6375 1475);
DISPLAY INVISIBLE (-6375 1475);
FORCEPROP 0 LAST CDS_SEC 1
J 0
(-6375 1475);
DISPLAY 1.021277 (-6375 1475);
DISPLAY INVISIBLE (-6375 1475);
FORCEPROP 1 LASTPIN (-6425 1400) $PN 1
J 0
(-6420 1362);
DISPLAY 0.489362 (-6420 1362);
PAINT MONO (-6420 1362);
FORCEPROP 1 LASTPIN (-6425 1200) $PN 2
J 0
(-6420 1210);
DISPLAY 0.489362 (-6420 1210);
PAINT MONO (-6420 1210);
FORCEPROP 1 LAST WATTAGE 1/16W
J 0
(-6385 1275);
DISPLAY 0.489362 (-6385 1275);
PAINT SKYBLUE (-6385 1275);
FORCEPROP 1 LAST MATERIAL CHIP
J 0
(-6385 1225);
DISPLAY 0.489362 (-6385 1225);
PAINT SKYBLUE (-6385 1225);
FORCEPROP 1 LAST TOLERANCE 1%
J 0
(-6380 1325);
DISPLAY 0.489362 (-6380 1325);
PAINT SKYBLUE (-6380 1325);
FORCEPROP 1 LAST VALUE 23.2K
J 0
(-6380 1375);
DISPLAY 0.489362 (-6380 1375);
PAINT SKYBLUE (-6380 1375);
FORCEPROP 1 LAST PACK_TYPE 0402LF
J 0
(-6385 1125);
DISPLAY 0.489362 (-6385 1125);
PAINT SKYBLUE (-6385 1125);
FORCEPROP 2 LAST CDS_LIB pure_quanta
J 0
(-6425 1300);
DISPLAY INVISIBLE (-6425 1300);
FORCEPROP 1 LAST PATH I128
J 0
(-6375 1475);
DISPLAY 0.978723 (-6375 1475);
PAINT WHITE (-6375 1475);
DISPLAY INVISIBLE (-6375 1475);
FORCEPROP 1 LAST PART_NUMBER CS32322FB03
J 0
(-6385 1175);
DISPLAY 0.489362 (-6385 1175);
PAINT SKYBLUE (-6385 1175);
DISPLAY INVISIBLE (-6385 1175);
FORCEADD OFFPAGE..1
(-8300 4200);
FORCEPROP 2 LAST $XR0 18 
J 0
(-8521 4200);
DISPLAY 0.638298 (-8521 4200);
PAINT MONO (-8521 4200);
FORCEPROP 2 LAST CDS_LIB mstr_standard
J 0
(-8300 4200);
DISPLAY 0.723404 (-8300 4200);
PAINT MONO (-8300 4200);
DISPLAY INVISIBLE (-8300 4200);
FORCEPROP 1 LAST OFFPAGE TRUE
J 0
(-7975 4075);
DISPLAY 0.872340 (-7975 4075);
PAINT GREEN (-7975 4075);
DISPLAY INVISIBLE (-7975 4075);
FORCEPROP 1 LAST COMMENT_BODY TRUE
J 0
(-8175 4100);
DISPLAY 0.872340 (-8175 4100);
PAINT GREEN (-8175 4100);
DISPLAY INVISIBLE (-8175 4100);
FORCEPROP 2 LAST PATH I13
J 0
(-8250 4275);
DISPLAY 1.021277 (-8250 4275);
DISPLAY INVISIBLE (-8250 4275);
FORCEADD OFFPAGE..1
(-8300 4300);
FORCEPROP 2 LAST $XR0 18 
J 0
(-8521 4300);
DISPLAY 0.638298 (-8521 4300);
PAINT MONO (-8521 4300);
FORCEPROP 2 LAST CDS_LIB mstr_standard
J 0
(-8300 4300);
DISPLAY 0.808511 (-8300 4300);
DISPLAY INVISIBLE (-8300 4300);
FORCEPROP 1 LAST OFFPAGE TRUE
J 0
(-7975 4175);
DISPLAY 0.872340 (-7975 4175);
PAINT GREEN (-7975 4175);
DISPLAY INVISIBLE (-7975 4175);
FORCEPROP 1 LAST COMMENT_BODY TRUE
J 0
(-8175 4200);
DISPLAY 0.872340 (-8175 4200);
PAINT GREEN (-8175 4200);
DISPLAY INVISIBLE (-8175 4200);
FORCEPROP 2 LAST PATH I14
J 0
(-8250 4375);
DISPLAY 1.021277 (-8250 4375);
DISPLAY INVISIBLE (-8250 4375);
FORCEADD GND..1
(-2125 2025);
FORCEPROP 3 LASTPIN (-2125 2075) SIG_NAME GND\g
J 0
(-2115 2085);
DISPLAY 0.659574 (-2115 2085);
PAINT MONO (-2115 2085);
DISPLAY INVISIBLE (-2115 2085);
FORCEPROP 1 LAST VOLTAGE 0.0
J 0
(-2170 1982);
DISPLAY 0.723404 (-2170 1982);
PAINT SKYBLUE (-2170 1982);
DISPLAY INVISIBLE (-2170 1982);
FORCEPROP 1 LAST SIZE 1B
J 0
(-2050 1975);
DISPLAY 0.851064 (-2050 1975);
PAINT GREEN (-2050 1975);
DISPLAY INVISIBLE (-2050 1975);
FORCEPROP 2 LAST CDS_LIB mstr_symbols
J 0
(-2125 2025);
DISPLAY 0.723404 (-2125 2025);
DISPLAY INVISIBLE (-2125 2025);
FORCEPROP 1 LAST BODY_TYPE PLUMBING
J 0
(-2170 1982);
DISPLAY 0.340426 (-2170 1982);
PAINT GREEN (-2170 1982);
DISPLAY INVISIBLE (-2170 1982);
FORCEPROP 1 LAST HDL_POWER GND
J 0
(-2125 2175);
DISPLAY 0.851064 (-2125 2175);
PAINT GREEN (-2125 2175);
DISPLAY INVISIBLE (-2125 2175);
FORCEPROP 1 LAST PATH I141
J 0
(-2050 2025);
DISPLAY 0.872340 (-2050 2025);
PAINT AQUA (-2050 2025);
DISPLAY INVISIBLE (-2050 2025);
FORCEADD GND..1
(-325 1800);
FORCEPROP 3 LASTPIN (-325 1850) SIG_NAME GND\g
J 0
(-315 1860);
DISPLAY 0.659574 (-315 1860);
PAINT MONO (-315 1860);
DISPLAY INVISIBLE (-315 1860);
FORCEPROP 1 LAST VOLTAGE 0.0
J 0
(-370 1757);
DISPLAY 0.723404 (-370 1757);
PAINT SKYBLUE (-370 1757);
DISPLAY INVISIBLE (-370 1757);
FORCEPROP 1 LAST SIZE 1B
J 0
(-250 1750);
DISPLAY 0.851064 (-250 1750);
PAINT GREEN (-250 1750);
DISPLAY INVISIBLE (-250 1750);
FORCEPROP 2 LAST CDS_LIB mstr_symbols
J 0
(-325 1800);
DISPLAY 0.723404 (-325 1800);
DISPLAY INVISIBLE (-325 1800);
FORCEPROP 1 LAST BODY_TYPE PLUMBING
J 0
(-370 1757);
DISPLAY 0.340426 (-370 1757);
PAINT GREEN (-370 1757);
DISPLAY INVISIBLE (-370 1757);
FORCEPROP 1 LAST HDL_POWER GND
J 0
(-325 1950);
DISPLAY 0.851064 (-325 1950);
PAINT GREEN (-325 1950);
DISPLAY INVISIBLE (-325 1950);
FORCEPROP 1 LAST PATH I142
J 0
(-250 1800);
DISPLAY 0.872340 (-250 1800);
PAINT AQUA (-250 1800);
DISPLAY INVISIBLE (-250 1800);
FORCEADD SCONN288_DDR506112002KQ..3
(-1225 3800);
FORCEPROP 1 LAST LOCATION J18
J 0
(-1675 5775);
DISPLAY 0.468085 (-1675 5775);
PAINT SKYBLUE (-1675 5775);
FORCEPROP 0 LAST $SEC 3
J 0
(-1675 5925);
DISPLAY 0.680851 (-1675 5925);
PAINT MONO (-1675 5925);
DISPLAY INVISIBLE (-1675 5925);
FORCEPROP 2 LAST CDS_SEC 3
J 0
(-1675 5925);
DISPLAY 1.021277 (-1675 5925);
DISPLAY INVISIBLE (-1675 5925);
FORCEPROP 0 LASTPIN (-625 2200) $PN G1
J 0
(-615 2210);
DISPLAY 0.680851 (-615 2210);
PAINT MONO (-615 2210);
FORCEPROP 0 LASTPIN (-625 2150) $PN G2
J 0
(-615 2160);
DISPLAY 0.680851 (-615 2160);
PAINT MONO (-615 2160);
FORCEPROP 0 LASTPIN (-625 2100) $PN G3
J 0
(-615 2110);
DISPLAY 0.680851 (-615 2110);
PAINT MONO (-615 2110);
FORCEPROP 0 LASTPIN (-1825 5350) $PN 1
J 2
(-1835 5360);
DISPLAY 0.680851 (-1835 5360);
PAINT MONO (-1835 5360);
FORCEPROP 0 LASTPIN (-1825 5400) $PN 145
J 2
(-1835 5410);
DISPLAY 0.680851 (-1835 5410);
PAINT MONO (-1835 5410);
FORCEPROP 0 LASTPIN (-1825 5450) $PN 146
J 2
(-1835 5460);
DISPLAY 0.680851 (-1835 5460);
PAINT MONO (-1835 5460);
FORCEPROP 0 LASTPIN (-625 2300) $PN 6
J 0
(-615 2310);
DISPLAY 0.680851 (-615 2310);
PAINT MONO (-615 2310);
FORCEPROP 0 LASTPIN (-625 2350) $PN 8
J 0
(-615 2360);
DISPLAY 0.680851 (-615 2360);
PAINT MONO (-615 2360);
FORCEPROP 0 LASTPIN (-625 2400) $PN 10
J 0
(-615 2410);
DISPLAY 0.680851 (-615 2410);
PAINT MONO (-615 2410);
FORCEPROP 0 LASTPIN (-625 2450) $PN 13
J 0
(-615 2460);
DISPLAY 0.680851 (-615 2460);
PAINT MONO (-615 2460);
FORCEPROP 0 LASTPIN (-625 2500) $PN 15
J 0
(-615 2510);
DISPLAY 0.680851 (-615 2510);
PAINT MONO (-615 2510);
FORCEPROP 0 LASTPIN (-625 2550) $PN 17
J 0
(-615 2560);
DISPLAY 0.680851 (-615 2560);
PAINT MONO (-615 2560);
FORCEPROP 0 LASTPIN (-625 2600) $PN 19
J 0
(-615 2610);
DISPLAY 0.680851 (-615 2610);
PAINT MONO (-615 2610);
FORCEPROP 0 LASTPIN (-625 2650) $PN 21
J 0
(-615 2660);
DISPLAY 0.680851 (-615 2660);
PAINT MONO (-615 2660);
FORCEPROP 0 LASTPIN (-625 2700) $PN 24
J 0
(-615 2710);
DISPLAY 0.680851 (-615 2710);
PAINT MONO (-615 2710);
FORCEPROP 0 LASTPIN (-625 2750) $PN 26
J 0
(-615 2760);
DISPLAY 0.680851 (-615 2760);
PAINT MONO (-615 2760);
FORCEPROP 0 LASTPIN (-625 2800) $PN 28
J 0
(-615 2810);
DISPLAY 0.680851 (-615 2810);
PAINT MONO (-615 2810);
FORCEPROP 0 LASTPIN (-625 2850) $PN 30
J 0
(-615 2860);
DISPLAY 0.680851 (-615 2860);
PAINT MONO (-615 2860);
FORCEPROP 0 LASTPIN (-625 2900) $PN 32
J 0
(-615 2910);
DISPLAY 0.680851 (-615 2910);
PAINT MONO (-615 2910);
FORCEPROP 0 LASTPIN (-625 2950) $PN 35
J 0
(-615 2960);
DISPLAY 0.680851 (-615 2960);
PAINT MONO (-615 2960);
FORCEPROP 0 LASTPIN (-625 3000) $PN 37
J 0
(-615 3010);
DISPLAY 0.680851 (-615 3010);
PAINT MONO (-615 3010);
FORCEPROP 0 LASTPIN (-625 3050) $PN 39
J 0
(-615 3060);
DISPLAY 0.680851 (-615 3060);
PAINT MONO (-615 3060);
FORCEPROP 0 LASTPIN (-625 3100) $PN 41
J 0
(-615 3110);
DISPLAY 0.680851 (-615 3110);
PAINT MONO (-615 3110);
FORCEPROP 0 LASTPIN (-625 3150) $PN 43
J 0
(-615 3160);
DISPLAY 0.680851 (-615 3160);
PAINT MONO (-615 3160);
FORCEPROP 0 LASTPIN (-625 3200) $PN 46
J 0
(-615 3210);
DISPLAY 0.680851 (-615 3210);
PAINT MONO (-615 3210);
FORCEPROP 0 LASTPIN (-625 3250) $PN 48
J 0
(-615 3260);
DISPLAY 0.680851 (-615 3260);
PAINT MONO (-615 3260);
FORCEPROP 0 LASTPIN (-625 3300) $PN 50
J 0
(-615 3310);
DISPLAY 0.680851 (-615 3310);
PAINT MONO (-615 3310);
FORCEPROP 0 LASTPIN (-625 3350) $PN 52
J 0
(-615 3360);
DISPLAY 0.680851 (-615 3360);
PAINT MONO (-615 3360);
FORCEPROP 0 LASTPIN (-625 3400) $PN 54
J 0
(-615 3410);
DISPLAY 0.680851 (-615 3410);
PAINT MONO (-615 3410);
FORCEPROP 0 LASTPIN (-625 3450) $PN 57
J 0
(-615 3460);
DISPLAY 0.680851 (-615 3460);
PAINT MONO (-615 3460);
FORCEPROP 0 LASTPIN (-625 3500) $PN 59
J 0
(-615 3510);
DISPLAY 0.680851 (-615 3510);
PAINT MONO (-615 3510);
FORCEPROP 0 LASTPIN (-625 3550) $PN 61
J 0
(-615 3560);
DISPLAY 0.680851 (-615 3560);
PAINT MONO (-615 3560);
FORCEPROP 0 LASTPIN (-625 3600) $PN 63
J 0
(-615 3610);
DISPLAY 0.680851 (-615 3610);
PAINT MONO (-615 3610);
FORCEPROP 0 LASTPIN (-625 3650) $PN 65
J 0
(-615 3660);
DISPLAY 0.680851 (-615 3660);
PAINT MONO (-615 3660);
FORCEPROP 0 LASTPIN (-625 3700) $PN 67
J 0
(-615 3710);
DISPLAY 0.680851 (-615 3710);
PAINT MONO (-615 3710);
FORCEPROP 0 LASTPIN (-625 3750) $PN 69
J 0
(-615 3760);
DISPLAY 0.680851 (-615 3760);
PAINT MONO (-615 3760);
FORCEPROP 0 LASTPIN (-625 3800) $PN 71
J 0
(-615 3810);
DISPLAY 0.680851 (-615 3810);
PAINT MONO (-615 3810);
FORCEPROP 0 LASTPIN (-625 3850) $PN 73
J 0
(-615 3860);
DISPLAY 0.680851 (-615 3860);
PAINT MONO (-615 3860);
FORCEPROP 0 LASTPIN (-625 3900) $PN 75
J 0
(-615 3910);
DISPLAY 0.680851 (-615 3910);
PAINT MONO (-615 3910);
FORCEPROP 0 LASTPIN (-625 3950) $PN 77
J 0
(-615 3960);
DISPLAY 0.680851 (-615 3960);
PAINT MONO (-615 3960);
FORCEPROP 0 LASTPIN (-625 4000) $PN 79
J 0
(-615 4010);
DISPLAY 0.680851 (-615 4010);
PAINT MONO (-615 4010);
FORCEPROP 0 LASTPIN (-625 4050) $PN 81
J 0
(-615 4060);
DISPLAY 0.680851 (-615 4060);
PAINT MONO (-615 4060);
FORCEPROP 0 LASTPIN (-625 4100) $PN 83
J 0
(-615 4110);
DISPLAY 0.680851 (-615 4110);
PAINT MONO (-615 4110);
FORCEPROP 0 LASTPIN (-625 4150) $PN 85
J 0
(-615 4160);
DISPLAY 0.680851 (-615 4160);
PAINT MONO (-615 4160);
FORCEPROP 0 LASTPIN (-625 4200) $PN 88
J 0
(-615 4210);
DISPLAY 0.680851 (-615 4210);
PAINT MONO (-615 4210);
FORCEPROP 0 LASTPIN (-625 4250) $PN 90
J 0
(-615 4260);
DISPLAY 0.680851 (-615 4260);
PAINT MONO (-615 4260);
FORCEPROP 0 LASTPIN (-625 4300) $PN 92
J 0
(-615 4310);
DISPLAY 0.680851 (-615 4310);
PAINT MONO (-615 4310);
FORCEPROP 0 LASTPIN (-625 4350) $PN 95
J 0
(-615 4360);
DISPLAY 0.680851 (-615 4360);
PAINT MONO (-615 4360);
FORCEPROP 0 LASTPIN (-625 4400) $PN 97
J 0
(-615 4410);
DISPLAY 0.680851 (-615 4410);
PAINT MONO (-615 4410);
FORCEPROP 0 LASTPIN (-625 4450) $PN 99
J 0
(-615 4460);
DISPLAY 0.680851 (-615 4460);
PAINT MONO (-615 4460);
FORCEPROP 0 LASTPIN (-625 4500) $PN 101
J 0
(-615 4510);
DISPLAY 0.680851 (-615 4510);
PAINT MONO (-615 4510);
FORCEPROP 0 LASTPIN (-625 4550) $PN 103
J 0
(-615 4560);
DISPLAY 0.680851 (-615 4560);
PAINT MONO (-615 4560);
FORCEPROP 0 LASTPIN (-625 4600) $PN 106
J 0
(-615 4610);
DISPLAY 0.680851 (-615 4610);
PAINT MONO (-615 4610);
FORCEPROP 0 LASTPIN (-625 4650) $PN 108
J 0
(-615 4660);
DISPLAY 0.680851 (-615 4660);
PAINT MONO (-615 4660);
FORCEPROP 0 LASTPIN (-625 4700) $PN 110
J 0
(-615 4710);
DISPLAY 0.680851 (-615 4710);
PAINT MONO (-615 4710);
FORCEPROP 0 LASTPIN (-625 4750) $PN 112
J 0
(-615 4760);
DISPLAY 0.680851 (-615 4760);
PAINT MONO (-615 4760);
FORCEPROP 0 LASTPIN (-625 4800) $PN 114
J 0
(-615 4810);
DISPLAY 0.680851 (-615 4810);
PAINT MONO (-615 4810);
FORCEPROP 0 LASTPIN (-625 4850) $PN 117
J 0
(-615 4860);
DISPLAY 0.680851 (-615 4860);
PAINT MONO (-615 4860);
FORCEPROP 0 LASTPIN (-625 4900) $PN 119
J 0
(-615 4910);
DISPLAY 0.680851 (-615 4910);
PAINT MONO (-615 4910);
FORCEPROP 0 LASTPIN (-625 4950) $PN 121
J 0
(-615 4960);
DISPLAY 0.680851 (-615 4960);
PAINT MONO (-615 4960);
FORCEPROP 0 LASTPIN (-625 5000) $PN 123
J 0
(-615 5010);
DISPLAY 0.680851 (-615 5010);
PAINT MONO (-615 5010);
FORCEPROP 0 LASTPIN (-625 5050) $PN 125
J 0
(-615 5060);
DISPLAY 0.680851 (-615 5060);
PAINT MONO (-615 5060);
FORCEPROP 0 LASTPIN (-625 5100) $PN 128
J 0
(-615 5110);
DISPLAY 0.680851 (-615 5110);
PAINT MONO (-615 5110);
FORCEPROP 0 LASTPIN (-625 5150) $PN 130
J 0
(-615 5160);
DISPLAY 0.680851 (-615 5160);
PAINT MONO (-615 5160);
FORCEPROP 0 LASTPIN (-625 5200) $PN 132
J 0
(-615 5210);
DISPLAY 0.680851 (-615 5210);
PAINT MONO (-615 5210);
FORCEPROP 0 LASTPIN (-625 5250) $PN 134
J 0
(-615 5260);
DISPLAY 0.680851 (-615 5260);
PAINT MONO (-615 5260);
FORCEPROP 0 LASTPIN (-625 5300) $PN 136
J 0
(-615 5310);
DISPLAY 0.680851 (-615 5310);
PAINT MONO (-615 5310);
FORCEPROP 0 LASTPIN (-625 5350) $PN 139
J 0
(-615 5360);
DISPLAY 0.680851 (-615 5360);
PAINT MONO (-615 5360);
FORCEPROP 0 LASTPIN (-625 5400) $PN 141
J 0
(-615 5410);
DISPLAY 0.680851 (-615 5410);
PAINT MONO (-615 5410);
FORCEPROP 0 LASTPIN (-625 5450) $PN 143
J 0
(-615 5460);
DISPLAY 0.680851 (-615 5460);
PAINT MONO (-615 5460);
FORCEPROP 0 LASTPIN (-1825 2200) $PN 151
J 2
(-1835 2210);
DISPLAY 0.680851 (-1835 2210);
PAINT MONO (-1835 2210);
FORCEPROP 0 LASTPIN (-1825 2250) $PN 153
J 2
(-1835 2260);
DISPLAY 0.680851 (-1835 2260);
PAINT MONO (-1835 2260);
FORCEPROP 0 LASTPIN (-1825 2300) $PN 155
J 2
(-1835 2310);
DISPLAY 0.680851 (-1835 2310);
PAINT MONO (-1835 2310);
FORCEPROP 0 LASTPIN (-1825 2350) $PN 158
J 2
(-1835 2360);
DISPLAY 0.680851 (-1835 2360);
PAINT MONO (-1835 2360);
FORCEPROP 0 LASTPIN (-1825 2400) $PN 160
J 2
(-1835 2410);
DISPLAY 0.680851 (-1835 2410);
PAINT MONO (-1835 2410);
FORCEPROP 0 LASTPIN (-1825 2450) $PN 162
J 2
(-1835 2460);
DISPLAY 0.680851 (-1835 2460);
PAINT MONO (-1835 2460);
FORCEPROP 0 LASTPIN (-1825 2500) $PN 164
J 2
(-1835 2510);
DISPLAY 0.680851 (-1835 2510);
PAINT MONO (-1835 2510);
FORCEPROP 0 LASTPIN (-1825 2550) $PN 166
J 2
(-1835 2560);
DISPLAY 0.680851 (-1835 2560);
PAINT MONO (-1835 2560);
FORCEPROP 0 LASTPIN (-1825 2600) $PN 169
J 2
(-1835 2610);
DISPLAY 0.680851 (-1835 2610);
PAINT MONO (-1835 2610);
FORCEPROP 0 LASTPIN (-1825 2650) $PN 171
J 2
(-1835 2660);
DISPLAY 0.680851 (-1835 2660);
PAINT MONO (-1835 2660);
FORCEPROP 0 LASTPIN (-1825 2700) $PN 173
J 2
(-1835 2710);
DISPLAY 0.680851 (-1835 2710);
PAINT MONO (-1835 2710);
FORCEPROP 0 LASTPIN (-1825 2750) $PN 175
J 2
(-1835 2760);
DISPLAY 0.680851 (-1835 2760);
PAINT MONO (-1835 2760);
FORCEPROP 0 LASTPIN (-1825 2800) $PN 177
J 2
(-1835 2810);
DISPLAY 0.680851 (-1835 2810);
PAINT MONO (-1835 2810);
FORCEPROP 0 LASTPIN (-1825 2850) $PN 180
J 2
(-1835 2860);
DISPLAY 0.680851 (-1835 2860);
PAINT MONO (-1835 2860);
FORCEPROP 0 LASTPIN (-1825 2900) $PN 182
J 2
(-1835 2910);
DISPLAY 0.680851 (-1835 2910);
PAINT MONO (-1835 2910);
FORCEPROP 0 LASTPIN (-1825 2950) $PN 184
J 2
(-1835 2960);
DISPLAY 0.680851 (-1835 2960);
PAINT MONO (-1835 2960);
FORCEPROP 0 LASTPIN (-1825 3000) $PN 186
J 2
(-1835 3010);
DISPLAY 0.680851 (-1835 3010);
PAINT MONO (-1835 3010);
FORCEPROP 0 LASTPIN (-1825 3050) $PN 188
J 2
(-1835 3060);
DISPLAY 0.680851 (-1835 3060);
PAINT MONO (-1835 3060);
FORCEPROP 0 LASTPIN (-1825 3100) $PN 191
J 2
(-1835 3110);
DISPLAY 0.680851 (-1835 3110);
PAINT MONO (-1835 3110);
FORCEPROP 0 LASTPIN (-1825 3150) $PN 193
J 2
(-1835 3160);
DISPLAY 0.680851 (-1835 3160);
PAINT MONO (-1835 3160);
FORCEPROP 0 LASTPIN (-1825 3200) $PN 195
J 2
(-1835 3210);
DISPLAY 0.680851 (-1835 3210);
PAINT MONO (-1835 3210);
FORCEPROP 0 LASTPIN (-1825 3250) $PN 197
J 2
(-1835 3260);
DISPLAY 0.680851 (-1835 3260);
PAINT MONO (-1835 3260);
FORCEPROP 0 LASTPIN (-1825 3300) $PN 199
J 2
(-1835 3310);
DISPLAY 0.680851 (-1835 3310);
PAINT MONO (-1835 3310);
FORCEPROP 0 LASTPIN (-1825 3350) $PN 202
J 2
(-1835 3360);
DISPLAY 0.680851 (-1835 3360);
PAINT MONO (-1835 3360);
FORCEPROP 0 LASTPIN (-1825 3400) $PN 204
J 2
(-1835 3410);
DISPLAY 0.680851 (-1835 3410);
PAINT MONO (-1835 3410);
FORCEPROP 0 LASTPIN (-1825 3450) $PN 206
J 2
(-1835 3460);
DISPLAY 0.680851 (-1835 3460);
PAINT MONO (-1835 3460);
FORCEPROP 0 LASTPIN (-1825 3500) $PN 208
J 2
(-1835 3510);
DISPLAY 0.680851 (-1835 3510);
PAINT MONO (-1835 3510);
FORCEPROP 0 LASTPIN (-1825 3550) $PN 210
J 2
(-1835 3560);
DISPLAY 0.680851 (-1835 3560);
PAINT MONO (-1835 3560);
FORCEPROP 0 LASTPIN (-1825 3600) $PN 212
J 2
(-1835 3610);
DISPLAY 0.680851 (-1835 3610);
PAINT MONO (-1835 3610);
FORCEPROP 0 LASTPIN (-1825 3650) $PN 214
J 2
(-1835 3660);
DISPLAY 0.680851 (-1835 3660);
PAINT MONO (-1835 3660);
FORCEPROP 0 LASTPIN (-1825 3700) $PN 216
J 2
(-1835 3710);
DISPLAY 0.680851 (-1835 3710);
PAINT MONO (-1835 3710);
FORCEPROP 0 LASTPIN (-1825 3750) $PN 219
J 2
(-1835 3760);
DISPLAY 0.680851 (-1835 3760);
PAINT MONO (-1835 3760);
FORCEPROP 0 LASTPIN (-1825 3800) $PN 222
J 2
(-1835 3810);
DISPLAY 0.680851 (-1835 3810);
PAINT MONO (-1835 3810);
FORCEPROP 0 LASTPIN (-1825 3850) $PN 224
J 2
(-1835 3860);
DISPLAY 0.680851 (-1835 3860);
PAINT MONO (-1835 3860);
FORCEPROP 0 LASTPIN (-1825 3900) $PN 226
J 2
(-1835 3910);
DISPLAY 0.680851 (-1835 3910);
PAINT MONO (-1835 3910);
FORCEPROP 0 LASTPIN (-1825 3950) $PN 228
J 2
(-1835 3960);
DISPLAY 0.680851 (-1835 3960);
PAINT MONO (-1835 3960);
FORCEPROP 0 LASTPIN (-1825 4000) $PN 230
J 2
(-1835 4010);
DISPLAY 0.680851 (-1835 4010);
PAINT MONO (-1835 4010);
FORCEPROP 0 LASTPIN (-1825 4050) $PN 233
J 2
(-1835 4060);
DISPLAY 0.680851 (-1835 4060);
PAINT MONO (-1835 4060);
FORCEPROP 0 LASTPIN (-1825 4100) $PN 235
J 2
(-1835 4110);
DISPLAY 0.680851 (-1835 4110);
PAINT MONO (-1835 4110);
FORCEPROP 0 LASTPIN (-1825 4150) $PN 237
J 2
(-1835 4160);
DISPLAY 0.680851 (-1835 4160);
PAINT MONO (-1835 4160);
FORCEPROP 0 LASTPIN (-1825 4200) $PN 240
J 2
(-1835 4210);
DISPLAY 0.680851 (-1835 4210);
PAINT MONO (-1835 4210);
FORCEPROP 0 LASTPIN (-1825 4250) $PN 242
J 2
(-1835 4260);
DISPLAY 0.680851 (-1835 4260);
PAINT MONO (-1835 4260);
FORCEPROP 0 LASTPIN (-1825 4300) $PN 244
J 2
(-1835 4310);
DISPLAY 0.680851 (-1835 4310);
PAINT MONO (-1835 4310);
FORCEPROP 0 LASTPIN (-1825 4350) $PN 246
J 2
(-1835 4360);
DISPLAY 0.680851 (-1835 4360);
PAINT MONO (-1835 4360);
FORCEPROP 0 LASTPIN (-1825 4400) $PN 248
J 2
(-1835 4410);
DISPLAY 0.680851 (-1835 4410);
PAINT MONO (-1835 4410);
FORCEPROP 0 LASTPIN (-1825 4450) $PN 251
J 2
(-1835 4460);
DISPLAY 0.680851 (-1835 4460);
PAINT MONO (-1835 4460);
FORCEPROP 0 LASTPIN (-1825 4500) $PN 253
J 2
(-1835 4510);
DISPLAY 0.680851 (-1835 4510);
PAINT MONO (-1835 4510);
FORCEPROP 0 LASTPIN (-1825 4550) $PN 255
J 2
(-1835 4560);
DISPLAY 0.680851 (-1835 4560);
PAINT MONO (-1835 4560);
FORCEPROP 0 LASTPIN (-1825 4600) $PN 257
J 2
(-1835 4610);
DISPLAY 0.680851 (-1835 4610);
PAINT MONO (-1835 4610);
FORCEPROP 0 LASTPIN (-1825 4650) $PN 259
J 2
(-1835 4660);
DISPLAY 0.680851 (-1835 4660);
PAINT MONO (-1835 4660);
FORCEPROP 0 LASTPIN (-1825 4700) $PN 262
J 2
(-1835 4710);
DISPLAY 0.680851 (-1835 4710);
PAINT MONO (-1835 4710);
FORCEPROP 0 LASTPIN (-1825 4750) $PN 264
J 2
(-1835 4760);
DISPLAY 0.680851 (-1835 4760);
PAINT MONO (-1835 4760);
FORCEPROP 0 LASTPIN (-1825 4800) $PN 266
J 2
(-1835 4810);
DISPLAY 0.680851 (-1835 4810);
PAINT MONO (-1835 4810);
FORCEPROP 0 LASTPIN (-1825 4850) $PN 268
J 2
(-1835 4860);
DISPLAY 0.680851 (-1835 4860);
PAINT MONO (-1835 4860);
FORCEPROP 0 LASTPIN (-1825 4900) $PN 270
J 2
(-1835 4910);
DISPLAY 0.680851 (-1835 4910);
PAINT MONO (-1835 4910);
FORCEPROP 0 LASTPIN (-1825 4950) $PN 273
J 2
(-1835 4960);
DISPLAY 0.680851 (-1835 4960);
PAINT MONO (-1835 4960);
FORCEPROP 0 LASTPIN (-1825 5000) $PN 275
J 2
(-1835 5010);
DISPLAY 0.680851 (-1835 5010);
PAINT MONO (-1835 5010);
FORCEPROP 0 LASTPIN (-1825 5050) $PN 277
J 2
(-1835 5060);
DISPLAY 0.680851 (-1835 5060);
PAINT MONO (-1835 5060);
FORCEPROP 0 LASTPIN (-1825 5100) $PN 279
J 2
(-1835 5110);
DISPLAY 0.680851 (-1835 5110);
PAINT MONO (-1835 5110);
FORCEPROP 0 LASTPIN (-1825 5150) $PN 281
J 2
(-1835 5160);
DISPLAY 0.680851 (-1835 5160);
PAINT MONO (-1835 5160);
FORCEPROP 0 LASTPIN (-1825 5200) $PN 284
J 2
(-1835 5210);
DISPLAY 0.680851 (-1835 5210);
PAINT MONO (-1835 5210);
FORCEPROP 0 LASTPIN (-1825 5250) $PN 286
J 2
(-1835 5260);
DISPLAY 0.680851 (-1835 5260);
PAINT MONO (-1835 5260);
FORCEPROP 0 LASTPIN (-1825 5300) $PN 288
J 2
(-1835 5310);
DISPLAY 0.680851 (-1835 5310);
PAINT MONO (-1835 5310);
FORCEPROP 1 LAST MATERIAL IO
J 0
(-1675 5625);
DISPLAY 0.468085 (-1675 5625);
PAINT SKYBLUE (-1675 5625);
FORCEPROP 2 LAST PART_TYPE SMLF
J 0
(-1675 5875);
DISPLAY 1.021277 (-1675 5875);
FORCEPROP 2 LAST VALUE SCONN288_DDR506112002KQ
J 0
(-1675 5825);
DISPLAY 0.489362 (-1675 5825);
PAINT SKYBLUE (-1675 5825);
FORCEPROP 2 LAST CDS_LIB pure_quanta
J 0
(-1225 3800);
DISPLAY INVISIBLE (-1225 3800);
FORCEPROP 1 LAST NEEDS_NO_SIZE TRUE
J 0
(-1225 3800);
DISPLAY 0.723404 (-1225 3800);
PAINT GREEN (-1225 3800);
DISPLAY INVISIBLE (-1225 3800);
FORCEPROP 1 LAST CDS_LMAN_SYM_OUTLINE -450,1800,450,-1750
J 0
(-1225 3800);
DISPLAY 0.468085 (-1225 3800);
PAINT GREEN (-1225 3800);
DISPLAY INVISIBLE (-1225 3800);
FORCEPROP 1 LAST PATH I143
J 0
(-1225 3800);
DISPLAY 0.723404 (-1225 3800);
PAINT GREEN (-1225 3800);
DISPLAY INVISIBLE (-1225 3800);
FORCEPROP 1 LAST PART_NUMBER DFHST8FS479
J 0
(-1675 5700);
DISPLAY 0.468085 (-1675 5700);
PAINT SKYBLUE (-1675 5700);
DISPLAY INVISIBLE (-1675 5700);
FORCEADD OFFPAGE..1
(-8300 4350);
FORCEPROP 2 LAST $XR0 18 
J 0
(-8521 4350);
DISPLAY 0.638298 (-8521 4350);
PAINT MONO (-8521 4350);
FORCEPROP 2 LAST CDS_LIB mstr_standard
J 0
(-8300 4350);
DISPLAY 0.723404 (-8300 4350);
PAINT MONO (-8300 4350);
DISPLAY INVISIBLE (-8300 4350);
FORCEPROP 1 LAST OFFPAGE TRUE
J 0
(-7975 4225);
DISPLAY 0.872340 (-7975 4225);
PAINT GREEN (-7975 4225);
DISPLAY INVISIBLE (-7975 4225);
FORCEPROP 1 LAST COMMENT_BODY TRUE
J 0
(-8175 4250);
DISPLAY 0.872340 (-8175 4250);
PAINT GREEN (-8175 4250);
DISPLAY INVISIBLE (-8175 4250);
FORCEPROP 2 LAST PATH I15
J 0
(-8250 4425);
DISPLAY 1.021277 (-8250 4425);
DISPLAY INVISIBLE (-8250 4425);
FORCEADD OFFPAGE..1
(-8300 4450);
FORCEPROP 2 LAST $XR0 18 
J 0
(-8521 4450);
DISPLAY 0.638298 (-8521 4450);
PAINT MONO (-8521 4450);
FORCEPROP 2 LAST CDS_LIB mstr_standard
J 0
(-8300 4450);
DISPLAY 0.808511 (-8300 4450);
DISPLAY INVISIBLE (-8300 4450);
FORCEPROP 1 LAST OFFPAGE TRUE
J 0
(-7975 4325);
DISPLAY 0.872340 (-7975 4325);
PAINT GREEN (-7975 4325);
DISPLAY INVISIBLE (-7975 4325);
FORCEPROP 1 LAST COMMENT_BODY TRUE
J 0
(-8175 4350);
DISPLAY 0.872340 (-8175 4350);
PAINT GREEN (-8175 4350);
DISPLAY INVISIBLE (-8175 4350);
FORCEPROP 2 LAST PATH I16
J 0
(-8250 4525);
DISPLAY 1.021277 (-8250 4525);
DISPLAY INVISIBLE (-8250 4525);
FORCEADD OFFPAGE..1
(-8300 4600);
FORCEPROP 2 LAST $XR0 18 
J 0
(-8521 4600);
DISPLAY 0.638298 (-8521 4600);
PAINT MONO (-8521 4600);
FORCEPROP 2 LAST CDS_LIB mstr_standard
J 0
(-8300 4600);
DISPLAY 0.808511 (-8300 4600);
DISPLAY INVISIBLE (-8300 4600);
FORCEPROP 1 LAST OFFPAGE TRUE
J 0
(-7975 4475);
DISPLAY 0.872340 (-7975 4475);
PAINT GREEN (-7975 4475);
DISPLAY INVISIBLE (-7975 4475);
FORCEPROP 1 LAST COMMENT_BODY TRUE
J 0
(-8175 4500);
DISPLAY 0.872340 (-8175 4500);
PAINT GREEN (-8175 4500);
DISPLAY INVISIBLE (-8175 4500);
FORCEPROP 2 LAST PATH I17
J 0
(-8250 4675);
DISPLAY 1.021277 (-8250 4675);
DISPLAY INVISIBLE (-8250 4675);
FORCEADD OFFPAGE..1
(-8300 4500);
FORCEPROP 2 LAST $XR0 18 
J 0
(-8521 4500);
DISPLAY 0.638298 (-8521 4500);
PAINT MONO (-8521 4500);
FORCEPROP 2 LAST CDS_LIB mstr_standard
J 0
(-8300 4500);
DISPLAY 0.723404 (-8300 4500);
PAINT MONO (-8300 4500);
DISPLAY INVISIBLE (-8300 4500);
FORCEPROP 1 LAST OFFPAGE TRUE
J 0
(-7975 4375);
DISPLAY 0.872340 (-7975 4375);
PAINT GREEN (-7975 4375);
DISPLAY INVISIBLE (-7975 4375);
FORCEPROP 1 LAST COMMENT_BODY TRUE
J 0
(-8175 4400);
DISPLAY 0.872340 (-8175 4400);
PAINT GREEN (-8175 4400);
DISPLAY INVISIBLE (-8175 4400);
FORCEPROP 2 LAST PATH I18
J 0
(-8250 4575);
DISPLAY 1.021277 (-8250 4575);
DISPLAY INVISIBLE (-8250 4575);
FORCEADD Q_CAP..1
R 2
(-8650 3275);
FORCEPROP 1 LAST LOCATION C120
J 2
(-8700 3375);
DISPLAY 0.489362 (-8700 3375);
PAINT SKYBLUE (-8700 3375);
FORCEPROP 0 LAST $SEC 1
J 0
(-8700 3425);
DISPLAY 0.680851 (-8700 3425);
PAINT MONO (-8700 3425);
DISPLAY INVISIBLE (-8700 3425);
FORCEPROP 0 LAST CDS_SEC 1
J 0
(-8700 3425);
DISPLAY 1.021277 (-8700 3425);
DISPLAY INVISIBLE (-8700 3425);
FORCEPROP 1 LASTPIN (-8650 3375) $PN 1
J 2
(-8660 3355);
DISPLAY 0.489362 (-8660 3355);
PAINT MONO (-8660 3355);
FORCEPROP 1 LASTPIN (-8650 3175) $PN 2
J 2
(-8660 3155);
DISPLAY 0.489362 (-8660 3155);
PAINT MONO (-8660 3155);
FORCEPROP 1 LAST TOLERANCE 10%
J 2
(-8700 3225);
DISPLAY 0.489362 (-8700 3225);
PAINT SKYBLUE (-8700 3225);
FORCEPROP 1 LAST MATERIAL X7R
J 2
(-8700 3175);
DISPLAY 0.489362 (-8700 3175);
PAINT SKYBLUE (-8700 3175);
FORCEPROP 1 LAST VALUE 0.1UF
J 2
(-8700 3325);
DISPLAY 0.489362 (-8700 3325);
PAINT SKYBLUE (-8700 3325);
FORCEPROP 1 LAST VOLTAGE 25V
J 2
(-8700 3275);
DISPLAY 0.489362 (-8700 3275);
PAINT SKYBLUE (-8700 3275);
FORCEPROP 1 LAST PACK_TYPE 0402
J 2
(-8700 3075);
DISPLAY 0.489362 (-8700 3075);
PAINT SKYBLUE (-8700 3075);
FORCEPROP 0 LAST BOM_COST MEM
J 2
(-8705 3420);
DISPLAY 0.595745 (-8705 3420);
PAINT MONO (-8705 3420);
DISPLAY INVISIBLE (-8705 3420);
FORCEPROP 2 LAST CDS_LIB pure_quanta
J 0
(-8650 3275);
DISPLAY INVISIBLE (-8650 3275);
FORCEPROP 2 LAST ROOM 
J 2
(-8705 3420);
DISPLAY 0.595745 (-8705 3420);
PAINT RED (-8705 3420);
DISPLAY INVISIBLE (-8705 3420);
FORCEPROP 1 LAST PATH I185
J 2
(-8700 3425);
DISPLAY 0.978723 (-8700 3425);
PAINT WHITE (-8700 3425);
DISPLAY INVISIBLE (-8700 3425);
FORCEPROP 1 LAST PART_NUMBER CH4104K1B00
J 2
(-8700 3125);
DISPLAY 0.489362 (-8700 3125);
PAINT SKYBLUE (-8700 3125);
DISPLAY INVISIBLE (-8700 3125);
FORCEADD GND..1
(-8650 3050);
FORCEPROP 3 LASTPIN (-8650 3100) SIG_NAME GND\g
J 0
(-8640 3110);
DISPLAY 0.659574 (-8640 3110);
PAINT MONO (-8640 3110);
DISPLAY INVISIBLE (-8640 3110);
FORCEPROP 2 LAST ROOM MEM_EFGH_DECOUPLING_CAPS
J 0
(-8625 3125);
DISPLAY 0.659574 (-8625 3125);
PAINT RED (-8625 3125);
DISPLAY INVISIBLE (-8625 3125);
FORCEPROP 1 LAST VOLTAGE 0
J 0
(-8670 3145);
DISPLAY 0.829787 (-8670 3145);
PAINT SKYBLUE (-8670 3145);
DISPLAY INVISIBLE (-8670 3145);
FORCEPROP 2 LAST CDS_LIB mstr_symbols
J 0
(-8650 3050);
DISPLAY 0.808511 (-8650 3050);
DISPLAY INVISIBLE (-8650 3050);
FORCEPROP 1 LAST SIZE 1B
J 0
(-8575 3000);
DISPLAY 0.723404 (-8575 3000);
PAINT GREEN (-8575 3000);
DISPLAY INVISIBLE (-8575 3000);
FORCEPROP 2 LAST BOM_COST MEM
J 0
(-8625 3175);
DISPLAY 0.659574 (-8625 3175);
DISPLAY INVISIBLE (-8625 3175);
FORCEPROP 1 LAST BODY_TYPE PLUMBING
J 0
(-8695 3007);
DISPLAY 0.276596 (-8695 3007);
PAINT GREEN (-8695 3007);
DISPLAY INVISIBLE (-8695 3007);
FORCEPROP 1 LAST HDL_POWER GND
J 0
(-8650 3200);
DISPLAY 0.723404 (-8650 3200);
PAINT GREEN (-8650 3200);
DISPLAY INVISIBLE (-8650 3200);
FORCEPROP 1 LAST PATH I186
J 0
(-8575 3050);
DISPLAY 0.872340 (-8575 3050);
PAINT AQUA (-8575 3050);
DISPLAY INVISIBLE (-8575 3050);
FORCEADD OFFPAGE..6
(-9025 2200);
FORCEPROP 2 LAST $XR4 97 
J 0
(-9274 2272);
DISPLAY 0.638298 (-9274 2272);
PAINT MONO (-9274 2272);
FORCEPROP 2 LAST $XR3 96 
J 0
(-9274 2128);
DISPLAY 0.638298 (-9274 2128);
PAINT MONO (-9274 2128);
FORCEPROP 2 LAST $XR2 95 
J 0
(-9274 2236);
DISPLAY 0.638298 (-9274 2236);
PAINT MONO (-9274 2236);
FORCEPROP 2 LAST $XR1 93 
J 0
(-9274 2164);
DISPLAY 0.638298 (-9274 2164);
PAINT MONO (-9274 2164);
FORCEPROP 2 LAST $XR0 92 
J 0
(-9274 2200);
DISPLAY 0.638298 (-9274 2200);
PAINT MONO (-9274 2200);
FORCEPROP 2 LAST CDS_LIB mstr_standard
J 0
(-9025 2200);
DISPLAY INVISIBLE (-9025 2200);
FORCEPROP 1 LAST OFFPAGE TRUE
J 0
(-8700 2075);
DISPLAY 0.872340 (-8700 2075);
PAINT GREEN (-8700 2075);
DISPLAY INVISIBLE (-8700 2075);
FORCEPROP 1 LAST COMMENT_BODY TRUE
J 0
(-8925 2125);
DISPLAY 0.872340 (-8925 2125);
PAINT GREEN (-8925 2125);
DISPLAY INVISIBLE (-8925 2125);
FORCEPROP 2 LAST PATH I187
J 0
(-8975 2275);
DISPLAY 1.021277 (-8975 2275);
DISPLAY INVISIBLE (-8975 2275);
FORCEADD Q_RES..1
R 2
(-8475 2200);
FORCEPROP 1 LAST LOCATION R299
J 2
(-8425 2250);
DISPLAY 0.489362 (-8425 2250);
PAINT SKYBLUE (-8425 2250);
FORCEPROP 0 LAST $SEC 1
J 0
(-8425 2300);
DISPLAY 0.680851 (-8425 2300);
PAINT MONO (-8425 2300);
DISPLAY INVISIBLE (-8425 2300);
FORCEPROP 0 LAST CDS_SEC 1
J 0
(-8425 2300);
DISPLAY 1.021277 (-8425 2300);
DISPLAY INVISIBLE (-8425 2300);
FORCEPROP 1 LASTPIN (-8375 2200) $PN 1
J 2
(-8387 2212);
DISPLAY 0.489362 (-8387 2212);
PAINT MONO (-8387 2212);
FORCEPROP 1 LASTPIN (-8575 2200) $PN 2
J 2
(-8537 2212);
DISPLAY 0.489362 (-8537 2212);
PAINT MONO (-8537 2212);
FORCEPROP 1 LAST VALUE 1K
J 0
(-8475 2150);
DISPLAY 0.489362 (-8475 2150);
PAINT SKYBLUE (-8475 2150);
FORCEPROP 1 LAST PACK_TYPE 0402LF
J 0
(-8650 2125);
DISPLAY 0.489362 (-8650 2125);
PAINT SKYBLUE (-8650 2125);
DISPLAY INVISIBLE (-8650 2125);
FORCEPROP 1 LAST MATERIAL CHIP
J 0
(-8650 2175);
DISPLAY 0.489362 (-8650 2175);
PAINT SKYBLUE (-8650 2175);
DISPLAY INVISIBLE (-8650 2175);
FORCEPROP 1 LAST WATTAGE 1/16W
J 0
(-8400 2125);
DISPLAY 0.489362 (-8400 2125);
PAINT SKYBLUE (-8400 2125);
DISPLAY INVISIBLE (-8400 2125);
FORCEPROP 2 LAST CDS_LIB pure_quanta
J 0
(-8475 2200);
DISPLAY INVISIBLE (-8475 2200);
FORCEPROP 2 LAST BOM_COST MEM
J 0
(-8500 2350);
DISPLAY 0.744681 (-8500 2350);
PAINT WHITE (-8500 2350);
DISPLAY INVISIBLE (-8500 2350);
FORCEPROP 1 LAST TOLERANCE 1%
J 2
(-8350 2175);
DISPLAY 0.489362 (-8350 2175);
PAINT SKYBLUE (-8350 2175);
DISPLAY INVISIBLE (-8350 2175);
FORCEPROP 2 LAST ROOM 
J 0
(-8500 2300);
DISPLAY 0.744681 (-8500 2300);
PAINT RED (-8500 2300);
DISPLAY INVISIBLE (-8500 2300);
FORCEPROP 1 LAST PATH I188
J 2
(-8425 2350);
DISPLAY 0.978723 (-8425 2350);
PAINT WHITE (-8425 2350);
DISPLAY INVISIBLE (-8425 2350);
FORCEPROP 1 LAST PART_NUMBER CS21002FB06
J 0
(-8575 2250);
DISPLAY 0.489362 (-8575 2250);
PAINT SKYBLUE (-8575 2250);
DISPLAY INVISIBLE (-8575 2250);
FORCEADD Q_RES..2
(-8350 2350);
FORCEPROP 1 LAST LOCATION R98
J 0
(-8305 2475);
DISPLAY 0.489362 (-8305 2475);
PAINT SKYBLUE (-8305 2475);
FORCEPROP 0 LAST $SEC 1
J 0
(-8300 2525);
DISPLAY 0.680851 (-8300 2525);
PAINT MONO (-8300 2525);
DISPLAY INVISIBLE (-8300 2525);
FORCEPROP 0 LAST CDS_SEC 1
J 0
(-8300 2525);
DISPLAY 1.021277 (-8300 2525);
DISPLAY INVISIBLE (-8300 2525);
FORCEPROP 1 LASTPIN (-8350 2450) $PN 1
J 0
(-8345 2412);
DISPLAY 0.489362 (-8345 2412);
PAINT MONO (-8345 2412);
FORCEPROP 1 LASTPIN (-8350 2250) $PN 2
J 0
(-8345 2260);
DISPLAY 0.489362 (-8345 2260);
PAINT MONO (-8345 2260);
FORCEPROP 1 LAST PACK_TYPE 0402LF
J 0
(-8300 2300);
DISPLAY 0.489362 (-8300 2300);
PAINT SKYBLUE (-8300 2300);
FORCEPROP 1 LAST VALUE 1K
J 0
(-8305 2425);
DISPLAY 0.489362 (-8305 2425);
PAINT SKYBLUE (-8305 2425);
FORCEPROP 1 LAST MATERIAL EMPTY
J 0
(-8300 2350);
DISPLAY 0.489362 (-8300 2350);
PAINT RED (-8300 2350);
FORCEPROP 1 LAST WATTAGE 1/16W
J 0
(-8300 2375);
DISPLAY 0.489362 (-8300 2375);
PAINT SKYBLUE (-8300 2375);
FORCEPROP 1 LAST TOLERANCE 1%
J 0
(-8300 2400);
DISPLAY 0.489362 (-8300 2400);
PAINT SKYBLUE (-8300 2400);
FORCEPROP 2 LAST CDS_LIB pure_quanta
J 0
(-8350 2350);
DISPLAY INVISIBLE (-8350 2350);
FORCEPROP 2 LAST BOM_COST MEM
J 0
(-8300 2525);
DISPLAY 0.808511 (-8300 2525);
DISPLAY INVISIBLE (-8300 2525);
FORCEPROP 2 LAST ROOM 
J 0
(-8300 2575);
DISPLAY 0.808511 (-8300 2575);
PAINT RED (-8300 2575);
DISPLAY INVISIBLE (-8300 2575);
FORCEPROP 1 LAST PATH I189
J 0
(-8300 2525);
DISPLAY 0.978723 (-8300 2525);
PAINT WHITE (-8300 2525);
DISPLAY INVISIBLE (-8300 2525);
FORCEPROP 1 LAST PART_NUMBER CS21002FB06
J 0
(-8300 2325);
DISPLAY 0.489362 (-8300 2325);
PAINT SKYBLUE (-8300 2325);
DISPLAY INVISIBLE (-8300 2325);
FORCEADD OFFPAGE..1
(-8300 4650);
FORCEPROP 2 LAST $XR0 18 
J 0
(-8521 4650);
DISPLAY 0.638298 (-8521 4650);
PAINT MONO (-8521 4650);
FORCEPROP 2 LAST CDS_LIB mstr_standard
J 0
(-8300 4650);
DISPLAY 0.723404 (-8300 4650);
PAINT MONO (-8300 4650);
DISPLAY INVISIBLE (-8300 4650);
FORCEPROP 1 LAST OFFPAGE TRUE
J 0
(-7975 4525);
DISPLAY 0.872340 (-7975 4525);
PAINT GREEN (-7975 4525);
DISPLAY INVISIBLE (-7975 4525);
FORCEPROP 1 LAST COMMENT_BODY TRUE
J 0
(-8175 4550);
DISPLAY 0.872340 (-8175 4550);
PAINT GREEN (-8175 4550);
DISPLAY INVISIBLE (-8175 4550);
FORCEPROP 2 LAST PATH I19
J 0
(-8250 4725);
DISPLAY 1.021277 (-8250 4725);
DISPLAY INVISIBLE (-8250 4725);
FORCEADD VCC_CORE..1
(-8350 2525);
FORCEPROP 3 LASTPIN (-8350 2475) SIG_NAME P3V3\g
J 0
(-8340 2485);
DISPLAY 0.659574 (-8340 2485);
PAINT MONO (-8340 2485);
DISPLAY INVISIBLE (-8340 2485);
FORCEPROP 1 LAST HDL_POWER P3V3
J 1
(-8350 2575);
DISPLAY 0.489362 (-8350 2575);
PAINT GREEN (-8350 2575);
FORCEPROP 2 LAST ROOM PVCCINFAON_CPU0_CTRL
J 0
(-8350 2625);
DISPLAY 0.808511 (-8350 2625);
PAINT RED (-8350 2625);
DISPLAY INVISIBLE (-8350 2625);
FORCEPROP 0 LAST VOLTAGE 3.3
J 0
(-8625 2675);
DISPLAY 1.021277 (-8625 2675);
PAINT SKYBLUE (-8625 2675);
DISPLAY INVISIBLE (-8625 2675);
FORCEPROP 2 LAST CDS_LIB mstr_symbols
J 0
(-8350 2525);
DISPLAY INVISIBLE (-8350 2525);
FORCEPROP 1 LAST PATH I190
J 0
(-8300 2550);
DISPLAY 0.872340 (-8300 2550);
PAINT AQUA (-8300 2550);
DISPLAY INVISIBLE (-8300 2550);
FORCEADD TAP..1
(-3450 4100);
FORCEPROP 3 LASTPIN (-3500 4100) SIG_NAME M_I_CPU0_SA_DQS_DP<5>
J 0
(-3490 4110);
DISPLAY 0.659574 (-3490 4110);
PAINT MONO (-3490 4110);
DISPLAY INVISIBLE (-3490 4110);
FORCEPROP 1 LASTPIN (-3500 4100) BN 5
J 0
(-3512 4108);
DISPLAY 0.489362 (-3512 4108);
PAINT GREEN (-3512 4108);
FORCEPROP 2 LAST CDS_LIB mstr_standard
J 0
(-3450 4100);
DISPLAY 0.723404 (-3450 4100);
PAINT MONO (-3450 4100);
DISPLAY INVISIBLE (-3450 4100);
FORCEPROP 1 LAST BODY_TYPE PLUMBING
J 0
(-3450 4150);
DISPLAY 0.872340 (-3450 4150);
PAINT GREEN (-3450 4150);
DISPLAY INVISIBLE (-3450 4150);
FORCEPROP 1 LAST HDL_TAP TRUE
J 0
(-3125 3975);
DISPLAY 0.872340 (-3125 3975);
DISPLAY INVISIBLE (-3125 3975);
FORCEPROP 1 LAST PATH I191
J 0
(-3452 4100);
DISPLAY 0.872340 (-3452 4100);
PAINT GREEN (-3452 4100);
DISPLAY INVISIBLE (-3452 4100);
FORCEADD OFFPAGE..2
(-2450 4550);
FORCEPROP 2 LAST $XR0 18 
J 0
(-2261 4550);
DISPLAY 0.638298 (-2261 4550);
PAINT MONO (-2261 4550);
FORCEPROP 2 LAST CDS_LIB mstr_standard
J 0
(-2450 4550);
DISPLAY 0.723404 (-2450 4550);
PAINT MONO (-2450 4550);
DISPLAY INVISIBLE (-2450 4550);
FORCEPROP 1 LAST OFFPAGE TRUE
J 0
(-2125 4425);
DISPLAY 0.723404 (-2125 4425);
PAINT GREEN (-2125 4425);
DISPLAY INVISIBLE (-2125 4425);
FORCEPROP 1 LAST COMMENT_BODY TRUE
J 0
(-2495 4455);
DISPLAY 0.872340 (-2495 4455);
PAINT GREEN (-2495 4455);
DISPLAY INVISIBLE (-2495 4455);
FORCEPROP 2 LAST PATH I193
J 0
(-2250 4600);
DISPLAY 0.680851 (-2250 4600);
DISPLAY INVISIBLE (-2250 4600);
FORCEADD OFFPAGE..2
(-2450 4500);
FORCEPROP 2 LAST $XR0 18 
J 0
(-2261 4500);
DISPLAY 0.638298 (-2261 4500);
PAINT MONO (-2261 4500);
FORCEPROP 2 LAST CDS_LIB mstr_standard
J 0
(-2450 4500);
DISPLAY 0.723404 (-2450 4500);
PAINT MONO (-2450 4500);
DISPLAY INVISIBLE (-2450 4500);
FORCEPROP 1 LAST OFFPAGE TRUE
J 0
(-2125 4375);
DISPLAY 0.723404 (-2125 4375);
PAINT GREEN (-2125 4375);
DISPLAY INVISIBLE (-2125 4375);
FORCEPROP 1 LAST COMMENT_BODY TRUE
J 0
(-2495 4405);
DISPLAY 0.872340 (-2495 4405);
PAINT GREEN (-2495 4405);
DISPLAY INVISIBLE (-2495 4405);
FORCEPROP 2 LAST PATH I194
J 0
(-2250 4550);
DISPLAY 0.680851 (-2250 4550);
DISPLAY INVISIBLE (-2250 4550);
FORCEADD OFFPAGE..2
(-2450 3500);
FORCEPROP 2 LAST $XR0 18 
J 0
(-2261 3500);
DISPLAY 0.638298 (-2261 3500);
PAINT MONO (-2261 3500);
FORCEPROP 2 LAST CDS_LIB mstr_standard
J 0
(-2450 3500);
DISPLAY 0.723404 (-2450 3500);
PAINT MONO (-2450 3500);
DISPLAY INVISIBLE (-2450 3500);
FORCEPROP 1 LAST OFFPAGE TRUE
J 0
(-2125 3375);
DISPLAY 0.723404 (-2125 3375);
PAINT GREEN (-2125 3375);
DISPLAY INVISIBLE (-2125 3375);
FORCEPROP 1 LAST COMMENT_BODY TRUE
J 0
(-2495 3405);
DISPLAY 0.872340 (-2495 3405);
PAINT GREEN (-2495 3405);
DISPLAY INVISIBLE (-2495 3405);
FORCEPROP 2 LAST PATH I195
J 0
(-2250 3550);
DISPLAY 0.680851 (-2250 3550);
DISPLAY INVISIBLE (-2250 3550);
FORCEADD OFFPAGE..2
(-2450 3450);
FORCEPROP 2 LAST $XR0 18 
J 0
(-2261 3450);
DISPLAY 0.638298 (-2261 3450);
PAINT MONO (-2261 3450);
FORCEPROP 2 LAST CDS_LIB mstr_standard
J 0
(-2450 3450);
DISPLAY 0.723404 (-2450 3450);
PAINT MONO (-2450 3450);
DISPLAY INVISIBLE (-2450 3450);
FORCEPROP 1 LAST OFFPAGE TRUE
J 0
(-2125 3325);
DISPLAY 0.723404 (-2125 3325);
PAINT GREEN (-2125 3325);
DISPLAY INVISIBLE (-2125 3325);
FORCEPROP 1 LAST COMMENT_BODY TRUE
J 0
(-2495 3355);
DISPLAY 0.872340 (-2495 3355);
PAINT GREEN (-2495 3355);
DISPLAY INVISIBLE (-2495 3355);
FORCEPROP 2 LAST PATH I196
J 0
(-2250 3500);
DISPLAY 0.680851 (-2250 3500);
DISPLAY INVISIBLE (-2250 3500);
FORCEADD TAP..1
(-3250 4450);
FORCEPROP 3 LASTPIN (-3300 4450) SIG_NAME M_I_CPU0_SA_DQS_DN<9>
J 0
(-3290 4460);
DISPLAY 0.659574 (-3290 4460);
PAINT MONO (-3290 4460);
DISPLAY INVISIBLE (-3290 4460);
FORCEPROP 1 LASTPIN (-3300 4450) BN 9
J 0
(-3312 4458);
DISPLAY 0.489362 (-3312 4458);
PAINT GREEN (-3312 4458);
FORCEPROP 2 LAST CDS_LIB mstr_standard
J 0
(-3250 4450);
DISPLAY 0.723404 (-3250 4450);
PAINT MONO (-3250 4450);
DISPLAY INVISIBLE (-3250 4450);
FORCEPROP 1 LAST BODY_TYPE PLUMBING
J 0
(-3250 4500);
DISPLAY 0.872340 (-3250 4500);
PAINT GREEN (-3250 4500);
DISPLAY INVISIBLE (-3250 4500);
FORCEPROP 1 LAST HDL_TAP TRUE
J 0
(-2925 4325);
DISPLAY 0.872340 (-2925 4325);
DISPLAY INVISIBLE (-2925 4325);
FORCEPROP 1 LAST PATH I197
J 0
(-3252 4450);
DISPLAY 0.872340 (-3252 4450);
PAINT GREEN (-3252 4450);
DISPLAY INVISIBLE (-3252 4450);
FORCEADD TAP..1
(-3250 4350);
FORCEPROP 3 LASTPIN (-3300 4350) SIG_NAME M_I_CPU0_SA_DQS_DN<8>
J 0
(-3290 4360);
DISPLAY 0.659574 (-3290 4360);
PAINT MONO (-3290 4360);
DISPLAY INVISIBLE (-3290 4360);
FORCEPROP 1 LASTPIN (-3300 4350) BN 8
J 0
(-3312 4358);
DISPLAY 0.489362 (-3312 4358);
PAINT GREEN (-3312 4358);
FORCEPROP 2 LAST CDS_LIB mstr_standard
J 0
(-3250 4350);
DISPLAY 0.723404 (-3250 4350);
PAINT MONO (-3250 4350);
DISPLAY INVISIBLE (-3250 4350);
FORCEPROP 1 LAST BODY_TYPE PLUMBING
J 0
(-3250 4400);
DISPLAY 0.872340 (-3250 4400);
PAINT GREEN (-3250 4400);
DISPLAY INVISIBLE (-3250 4400);
FORCEPROP 1 LAST HDL_TAP TRUE
J 0
(-2925 4225);
DISPLAY 0.872340 (-2925 4225);
DISPLAY INVISIBLE (-2925 4225);
FORCEPROP 1 LAST PATH I198
J 0
(-3252 4350);
DISPLAY 0.872340 (-3252 4350);
PAINT GREEN (-3252 4350);
DISPLAY INVISIBLE (-3252 4350);
FORCEADD TAP..1
(-3450 4400);
FORCEPROP 3 LASTPIN (-3500 4400) SIG_NAME M_I_CPU0_SA_DQS_DP<8>
J 0
(-3490 4410);
DISPLAY 0.659574 (-3490 4410);
PAINT MONO (-3490 4410);
DISPLAY INVISIBLE (-3490 4410);
FORCEPROP 1 LASTPIN (-3500 4400) BN 8
J 0
(-3512 4408);
DISPLAY 0.489362 (-3512 4408);
PAINT GREEN (-3512 4408);
FORCEPROP 2 LAST CDS_LIB mstr_standard
J 0
(-3450 4400);
DISPLAY 0.723404 (-3450 4400);
PAINT MONO (-3450 4400);
DISPLAY INVISIBLE (-3450 4400);
FORCEPROP 1 LAST BODY_TYPE PLUMBING
J 0
(-3450 4450);
DISPLAY 0.872340 (-3450 4450);
PAINT GREEN (-3450 4450);
DISPLAY INVISIBLE (-3450 4450);
FORCEPROP 1 LAST HDL_TAP TRUE
J 0
(-3125 4275);
DISPLAY 0.872340 (-3125 4275);
DISPLAY INVISIBLE (-3125 4275);
FORCEPROP 1 LAST PATH I199
J 0
(-3452 4400);
DISPLAY 0.872340 (-3452 4400);
PAINT GREEN (-3452 4400);
DISPLAY INVISIBLE (-3452 4400);
FORCEADD OFFPAGE..5
(-8300 2050);
FORCEPROP 2 LAST $XR0 18 
J 0
(-8554 2050);
DISPLAY 0.638298 (-8554 2050);
PAINT MONO (-8554 2050);
FORCEPROP 2 LAST CDS_LIB mstr_standard
J 0
(-8300 2050);
DISPLAY 0.808511 (-8300 2050);
DISPLAY INVISIBLE (-8300 2050);
FORCEPROP 1 LAST OFFPAGE TRUE
J 0
(-7975 1925);
DISPLAY 0.872340 (-7975 1925);
PAINT GREEN (-7975 1925);
DISPLAY INVISIBLE (-7975 1925);
FORCEPROP 1 LAST COMMENT_BODY TRUE
J 0
(-8200 1975);
DISPLAY 0.872340 (-8200 1975);
PAINT GREEN (-8200 1975);
DISPLAY INVISIBLE (-8200 1975);
FORCEPROP 2 LAST PATH I2
J 0
(-8250 2125);
DISPLAY 1.021277 (-8250 2125);
DISPLAY INVISIBLE (-8250 2125);
FORCEADD OFFPAGE..1
(-8300 5100);
FORCEPROP 2 LAST $XR0 18 
J 0
(-8521 5100);
DISPLAY 0.638298 (-8521 5100);
PAINT MONO (-8521 5100);
FORCEPROP 2 LAST CDS_LIB mstr_standard
J 0
(-8300 5100);
DISPLAY 0.723404 (-8300 5100);
PAINT MONO (-8300 5100);
DISPLAY INVISIBLE (-8300 5100);
FORCEPROP 1 LAST OFFPAGE TRUE
J 0
(-7975 4975);
DISPLAY 0.872340 (-7975 4975);
PAINT GREEN (-7975 4975);
DISPLAY INVISIBLE (-7975 4975);
FORCEPROP 1 LAST COMMENT_BODY TRUE
J 0
(-8175 5000);
DISPLAY 0.872340 (-8175 5000);
PAINT GREEN (-8175 5000);
DISPLAY INVISIBLE (-8175 5000);
FORCEPROP 2 LAST PATH I20
J 0
(-8250 5175);
DISPLAY 1.021277 (-8250 5175);
DISPLAY INVISIBLE (-8250 5175);
FORCEADD TAP..1
(-3450 4500);
FORCEPROP 3 LASTPIN (-3500 4500) SIG_NAME M_I_CPU0_SA_DQS_DP<9>
J 0
(-3490 4510);
DISPLAY 0.659574 (-3490 4510);
PAINT MONO (-3490 4510);
DISPLAY INVISIBLE (-3490 4510);
FORCEPROP 1 LASTPIN (-3500 4500) BN 9
J 0
(-3512 4508);
DISPLAY 0.489362 (-3512 4508);
PAINT GREEN (-3512 4508);
FORCEPROP 2 LAST CDS_LIB mstr_standard
J 0
(-3450 4500);
DISPLAY 0.723404 (-3450 4500);
PAINT MONO (-3450 4500);
DISPLAY INVISIBLE (-3450 4500);
FORCEPROP 1 LAST BODY_TYPE PLUMBING
J 0
(-3450 4550);
DISPLAY 0.872340 (-3450 4550);
PAINT GREEN (-3450 4550);
DISPLAY INVISIBLE (-3450 4550);
FORCEPROP 1 LAST HDL_TAP TRUE
J 0
(-3125 4375);
DISPLAY 0.872340 (-3125 4375);
DISPLAY INVISIBLE (-3125 4375);
FORCEPROP 1 LAST PATH I200
J 0
(-3452 4500);
DISPLAY 0.872340 (-3452 4500);
PAINT GREEN (-3452 4500);
DISPLAY INVISIBLE (-3452 4500);
FORCEADD TAP..1
(-3250 4250);
FORCEPROP 3 LASTPIN (-3300 4250) SIG_NAME M_I_CPU0_SA_DQS_DN<7>
J 0
(-3290 4260);
DISPLAY 0.659574 (-3290 4260);
PAINT MONO (-3290 4260);
DISPLAY INVISIBLE (-3290 4260);
FORCEPROP 1 LASTPIN (-3300 4250) BN 7
J 0
(-3312 4258);
DISPLAY 0.489362 (-3312 4258);
PAINT GREEN (-3312 4258);
FORCEPROP 2 LAST CDS_LIB mstr_standard
J 0
(-3250 4250);
DISPLAY 0.723404 (-3250 4250);
PAINT MONO (-3250 4250);
DISPLAY INVISIBLE (-3250 4250);
FORCEPROP 1 LAST BODY_TYPE PLUMBING
J 0
(-3250 4300);
DISPLAY 0.872340 (-3250 4300);
PAINT GREEN (-3250 4300);
DISPLAY INVISIBLE (-3250 4300);
FORCEPROP 1 LAST HDL_TAP TRUE
J 0
(-2925 4125);
DISPLAY 0.872340 (-2925 4125);
DISPLAY INVISIBLE (-2925 4125);
FORCEPROP 1 LAST PATH I201
J 0
(-3252 4250);
DISPLAY 0.872340 (-3252 4250);
PAINT GREEN (-3252 4250);
DISPLAY INVISIBLE (-3252 4250);
FORCEADD TAP..1
(-3250 4150);
FORCEPROP 3 LASTPIN (-3300 4150) SIG_NAME M_I_CPU0_SA_DQS_DN<6>
J 0
(-3290 4160);
DISPLAY 0.659574 (-3290 4160);
PAINT MONO (-3290 4160);
DISPLAY INVISIBLE (-3290 4160);
FORCEPROP 1 LASTPIN (-3300 4150) BN 6
J 0
(-3312 4158);
DISPLAY 0.489362 (-3312 4158);
PAINT GREEN (-3312 4158);
FORCEPROP 2 LAST CDS_LIB mstr_standard
J 0
(-3250 4150);
DISPLAY 0.723404 (-3250 4150);
PAINT MONO (-3250 4150);
DISPLAY INVISIBLE (-3250 4150);
FORCEPROP 1 LAST BODY_TYPE PLUMBING
J 0
(-3250 4200);
DISPLAY 0.872340 (-3250 4200);
PAINT GREEN (-3250 4200);
DISPLAY INVISIBLE (-3250 4200);
FORCEPROP 1 LAST HDL_TAP TRUE
J 0
(-2925 4025);
DISPLAY 0.872340 (-2925 4025);
DISPLAY INVISIBLE (-2925 4025);
FORCEPROP 1 LAST PATH I202
J 0
(-3252 4150);
DISPLAY 0.872340 (-3252 4150);
PAINT GREEN (-3252 4150);
DISPLAY INVISIBLE (-3252 4150);
FORCEADD TAP..1
(-3250 4050);
FORCEPROP 3 LASTPIN (-3300 4050) SIG_NAME M_I_CPU0_SA_DQS_DN<5>
J 0
(-3290 4060);
DISPLAY 0.659574 (-3290 4060);
PAINT MONO (-3290 4060);
DISPLAY INVISIBLE (-3290 4060);
FORCEPROP 1 LASTPIN (-3300 4050) BN 5
J 0
(-3312 4058);
DISPLAY 0.489362 (-3312 4058);
PAINT GREEN (-3312 4058);
FORCEPROP 2 LAST CDS_LIB mstr_standard
J 0
(-3250 4050);
DISPLAY 0.723404 (-3250 4050);
PAINT MONO (-3250 4050);
DISPLAY INVISIBLE (-3250 4050);
FORCEPROP 1 LAST BODY_TYPE PLUMBING
J 0
(-3250 4100);
DISPLAY 0.872340 (-3250 4100);
PAINT GREEN (-3250 4100);
DISPLAY INVISIBLE (-3250 4100);
FORCEPROP 1 LAST HDL_TAP TRUE
J 0
(-2925 3925);
DISPLAY 0.872340 (-2925 3925);
DISPLAY INVISIBLE (-2925 3925);
FORCEPROP 1 LAST PATH I203
J 0
(-3252 4050);
DISPLAY 0.872340 (-3252 4050);
PAINT GREEN (-3252 4050);
DISPLAY INVISIBLE (-3252 4050);
FORCEADD TAP..1
(-3250 3950);
FORCEPROP 3 LASTPIN (-3300 3950) SIG_NAME M_I_CPU0_SA_DQS_DN<4>
J 0
(-3290 3960);
DISPLAY 0.659574 (-3290 3960);
PAINT MONO (-3290 3960);
DISPLAY INVISIBLE (-3290 3960);
FORCEPROP 1 LASTPIN (-3300 3950) BN 4
J 0
(-3312 3958);
DISPLAY 0.489362 (-3312 3958);
PAINT GREEN (-3312 3958);
FORCEPROP 2 LAST CDS_LIB mstr_standard
J 0
(-3250 3950);
DISPLAY 0.723404 (-3250 3950);
PAINT MONO (-3250 3950);
DISPLAY INVISIBLE (-3250 3950);
FORCEPROP 1 LAST BODY_TYPE PLUMBING
J 0
(-3250 4000);
DISPLAY 0.872340 (-3250 4000);
PAINT GREEN (-3250 4000);
DISPLAY INVISIBLE (-3250 4000);
FORCEPROP 1 LAST HDL_TAP TRUE
J 0
(-2925 3825);
DISPLAY 0.872340 (-2925 3825);
DISPLAY INVISIBLE (-2925 3825);
FORCEPROP 1 LAST PATH I204
J 0
(-3252 3950);
DISPLAY 0.872340 (-3252 3950);
PAINT GREEN (-3252 3950);
DISPLAY INVISIBLE (-3252 3950);
FORCEADD TAP..1
(-3250 3850);
FORCEPROP 3 LASTPIN (-3300 3850) SIG_NAME M_I_CPU0_SA_DQS_DN<3>
J 0
(-3290 3860);
DISPLAY 0.659574 (-3290 3860);
PAINT MONO (-3290 3860);
DISPLAY INVISIBLE (-3290 3860);
FORCEPROP 1 LASTPIN (-3300 3850) BN 3
J 0
(-3312 3858);
DISPLAY 0.489362 (-3312 3858);
PAINT GREEN (-3312 3858);
FORCEPROP 2 LAST CDS_LIB mstr_standard
J 0
(-3250 3850);
DISPLAY 0.723404 (-3250 3850);
PAINT MONO (-3250 3850);
DISPLAY INVISIBLE (-3250 3850);
FORCEPROP 1 LAST BODY_TYPE PLUMBING
J 0
(-3250 3900);
DISPLAY 0.872340 (-3250 3900);
PAINT GREEN (-3250 3900);
DISPLAY INVISIBLE (-3250 3900);
FORCEPROP 1 LAST HDL_TAP TRUE
J 0
(-2925 3725);
DISPLAY 0.872340 (-2925 3725);
DISPLAY INVISIBLE (-2925 3725);
FORCEPROP 1 LAST PATH I205
J 0
(-3252 3850);
DISPLAY 0.872340 (-3252 3850);
PAINT GREEN (-3252 3850);
DISPLAY INVISIBLE (-3252 3850);
FORCEADD TAP..1
(-3250 3750);
FORCEPROP 3 LASTPIN (-3300 3750) SIG_NAME M_I_CPU0_SA_DQS_DN<2>
J 0
(-3290 3760);
DISPLAY 0.659574 (-3290 3760);
PAINT MONO (-3290 3760);
DISPLAY INVISIBLE (-3290 3760);
FORCEPROP 1 LASTPIN (-3300 3750) BN 2
J 0
(-3312 3758);
DISPLAY 0.489362 (-3312 3758);
PAINT GREEN (-3312 3758);
FORCEPROP 2 LAST CDS_LIB mstr_standard
J 0
(-3250 3750);
DISPLAY 0.723404 (-3250 3750);
PAINT MONO (-3250 3750);
DISPLAY INVISIBLE (-3250 3750);
FORCEPROP 1 LAST BODY_TYPE PLUMBING
J 0
(-3250 3800);
DISPLAY 0.872340 (-3250 3800);
PAINT GREEN (-3250 3800);
DISPLAY INVISIBLE (-3250 3800);
FORCEPROP 1 LAST HDL_TAP TRUE
J 0
(-2925 3625);
DISPLAY 0.872340 (-2925 3625);
DISPLAY INVISIBLE (-2925 3625);
FORCEPROP 1 LAST PATH I206
J 0
(-3252 3750);
DISPLAY 0.872340 (-3252 3750);
PAINT GREEN (-3252 3750);
DISPLAY INVISIBLE (-3252 3750);
FORCEADD TAP..1
(-3250 3650);
FORCEPROP 3 LASTPIN (-3300 3650) SIG_NAME M_I_CPU0_SA_DQS_DN<1>
J 0
(-3290 3660);
DISPLAY 0.659574 (-3290 3660);
PAINT MONO (-3290 3660);
DISPLAY INVISIBLE (-3290 3660);
FORCEPROP 1 LASTPIN (-3300 3650) BN 1
J 0
(-3312 3658);
DISPLAY 0.489362 (-3312 3658);
PAINT GREEN (-3312 3658);
FORCEPROP 2 LAST CDS_LIB mstr_standard
J 0
(-3250 3650);
DISPLAY 0.723404 (-3250 3650);
PAINT MONO (-3250 3650);
DISPLAY INVISIBLE (-3250 3650);
FORCEPROP 1 LAST BODY_TYPE PLUMBING
J 0
(-3250 3700);
DISPLAY 0.872340 (-3250 3700);
PAINT GREEN (-3250 3700);
DISPLAY INVISIBLE (-3250 3700);
FORCEPROP 1 LAST HDL_TAP TRUE
J 0
(-2925 3525);
DISPLAY 0.872340 (-2925 3525);
DISPLAY INVISIBLE (-2925 3525);
FORCEPROP 1 LAST PATH I207
J 0
(-3252 3650);
DISPLAY 0.872340 (-3252 3650);
PAINT GREEN (-3252 3650);
DISPLAY INVISIBLE (-3252 3650);
FORCEADD TAP..1
(-3250 3400);
FORCEPROP 3 LASTPIN (-3300 3400) SIG_NAME M_I_CPU0_SB_DQS_DN<9>
J 0
(-3290 3410);
DISPLAY 0.659574 (-3290 3410);
PAINT MONO (-3290 3410);
DISPLAY INVISIBLE (-3290 3410);
FORCEPROP 1 LASTPIN (-3300 3400) BN 9
J 0
(-3312 3408);
DISPLAY 0.489362 (-3312 3408);
PAINT GREEN (-3312 3408);
FORCEPROP 2 LAST CDS_LIB mstr_standard
J 0
(-3250 3400);
DISPLAY 0.723404 (-3250 3400);
PAINT MONO (-3250 3400);
DISPLAY INVISIBLE (-3250 3400);
FORCEPROP 1 LAST BODY_TYPE PLUMBING
J 0
(-3250 3450);
DISPLAY 0.872340 (-3250 3450);
PAINT GREEN (-3250 3450);
DISPLAY INVISIBLE (-3250 3450);
FORCEPROP 1 LAST HDL_TAP TRUE
J 0
(-2925 3275);
DISPLAY 0.872340 (-2925 3275);
DISPLAY INVISIBLE (-2925 3275);
FORCEPROP 1 LAST PATH I208
J 0
(-3252 3400);
DISPLAY 0.872340 (-3252 3400);
PAINT GREEN (-3252 3400);
DISPLAY INVISIBLE (-3252 3400);
FORCEADD TAP..1
(-3250 3550);
FORCEPROP 3 LASTPIN (-3300 3550) SIG_NAME M_I_CPU0_SA_DQS_DN<0>
J 0
(-3290 3560);
DISPLAY 0.659574 (-3290 3560);
PAINT MONO (-3290 3560);
DISPLAY INVISIBLE (-3290 3560);
FORCEPROP 1 LASTPIN (-3300 3550) BN 0
J 0
(-3312 3558);
DISPLAY 0.489362 (-3312 3558);
PAINT GREEN (-3312 3558);
FORCEPROP 2 LAST CDS_LIB mstr_standard
J 0
(-3250 3550);
DISPLAY 0.723404 (-3250 3550);
PAINT MONO (-3250 3550);
DISPLAY INVISIBLE (-3250 3550);
FORCEPROP 1 LAST BODY_TYPE PLUMBING
J 0
(-3250 3600);
DISPLAY 0.872340 (-3250 3600);
PAINT GREEN (-3250 3600);
DISPLAY INVISIBLE (-3250 3600);
FORCEPROP 1 LAST HDL_TAP TRUE
J 0
(-2925 3425);
DISPLAY 0.872340 (-2925 3425);
DISPLAY INVISIBLE (-2925 3425);
FORCEPROP 1 LAST PATH I209
J 0
(-3252 3550);
DISPLAY 0.872340 (-3252 3550);
PAINT GREEN (-3252 3550);
DISPLAY INVISIBLE (-3252 3550);
FORCEADD OFFPAGE..1
(-8300 5500);
FORCEPROP 2 LAST $XR0 18 
J 0
(-8521 5500);
DISPLAY 0.638298 (-8521 5500);
PAINT MONO (-8521 5500);
FORCEPROP 2 LAST CDS_LIB mstr_standard
J 0
(-8300 5500);
DISPLAY 0.723404 (-8300 5500);
PAINT MONO (-8300 5500);
DISPLAY INVISIBLE (-8300 5500);
FORCEPROP 1 LAST OFFPAGE TRUE
J 0
(-7975 5375);
DISPLAY 0.872340 (-7975 5375);
PAINT GREEN (-7975 5375);
DISPLAY INVISIBLE (-7975 5375);
FORCEPROP 1 LAST COMMENT_BODY TRUE
J 0
(-8175 5400);
DISPLAY 0.872340 (-8175 5400);
PAINT GREEN (-8175 5400);
DISPLAY INVISIBLE (-8175 5400);
FORCEPROP 2 LAST PATH I21
J 0
(-8250 5575);
DISPLAY 1.021277 (-8250 5575);
DISPLAY INVISIBLE (-8250 5575);
FORCEADD TAP..1
(-3450 4300);
FORCEPROP 3 LASTPIN (-3500 4300) SIG_NAME M_I_CPU0_SA_DQS_DP<7>
J 0
(-3490 4310);
DISPLAY 0.659574 (-3490 4310);
PAINT MONO (-3490 4310);
DISPLAY INVISIBLE (-3490 4310);
FORCEPROP 1 LASTPIN (-3500 4300) BN 7
J 0
(-3512 4308);
DISPLAY 0.489362 (-3512 4308);
PAINT GREEN (-3512 4308);
FORCEPROP 2 LAST CDS_LIB mstr_standard
J 0
(-3450 4300);
DISPLAY 0.723404 (-3450 4300);
PAINT MONO (-3450 4300);
DISPLAY INVISIBLE (-3450 4300);
FORCEPROP 1 LAST BODY_TYPE PLUMBING
J 0
(-3450 4350);
DISPLAY 0.872340 (-3450 4350);
PAINT GREEN (-3450 4350);
DISPLAY INVISIBLE (-3450 4350);
FORCEPROP 1 LAST HDL_TAP TRUE
J 0
(-3125 4175);
DISPLAY 0.872340 (-3125 4175);
DISPLAY INVISIBLE (-3125 4175);
FORCEPROP 1 LAST PATH I210
J 0
(-3452 4300);
DISPLAY 0.872340 (-3452 4300);
PAINT GREEN (-3452 4300);
DISPLAY INVISIBLE (-3452 4300);
FORCEADD TAP..1
(-3450 4200);
FORCEPROP 3 LASTPIN (-3500 4200) SIG_NAME M_I_CPU0_SA_DQS_DP<6>
J 0
(-3490 4210);
DISPLAY 0.659574 (-3490 4210);
PAINT MONO (-3490 4210);
DISPLAY INVISIBLE (-3490 4210);
FORCEPROP 1 LASTPIN (-3500 4200) BN 6
J 0
(-3512 4208);
DISPLAY 0.489362 (-3512 4208);
PAINT GREEN (-3512 4208);
FORCEPROP 2 LAST CDS_LIB mstr_standard
J 0
(-3450 4200);
DISPLAY 0.723404 (-3450 4200);
PAINT MONO (-3450 4200);
DISPLAY INVISIBLE (-3450 4200);
FORCEPROP 1 LAST BODY_TYPE PLUMBING
J 0
(-3450 4250);
DISPLAY 0.872340 (-3450 4250);
PAINT GREEN (-3450 4250);
DISPLAY INVISIBLE (-3450 4250);
FORCEPROP 1 LAST HDL_TAP TRUE
J 0
(-3125 4075);
DISPLAY 0.872340 (-3125 4075);
DISPLAY INVISIBLE (-3125 4075);
FORCEPROP 1 LAST PATH I211
J 0
(-3452 4200);
DISPLAY 0.872340 (-3452 4200);
PAINT GREEN (-3452 4200);
DISPLAY INVISIBLE (-3452 4200);
FORCEADD TAP..1
(-3450 4000);
FORCEPROP 3 LASTPIN (-3500 4000) SIG_NAME M_I_CPU0_SA_DQS_DP<4>
J 0
(-3490 4010);
DISPLAY 0.659574 (-3490 4010);
PAINT MONO (-3490 4010);
DISPLAY INVISIBLE (-3490 4010);
FORCEPROP 1 LASTPIN (-3500 4000) BN 4
J 0
(-3512 4008);
DISPLAY 0.489362 (-3512 4008);
PAINT GREEN (-3512 4008);
FORCEPROP 2 LAST CDS_LIB mstr_standard
J 0
(-3450 4000);
DISPLAY 0.723404 (-3450 4000);
PAINT MONO (-3450 4000);
DISPLAY INVISIBLE (-3450 4000);
FORCEPROP 1 LAST BODY_TYPE PLUMBING
J 0
(-3450 4050);
DISPLAY 0.872340 (-3450 4050);
PAINT GREEN (-3450 4050);
DISPLAY INVISIBLE (-3450 4050);
FORCEPROP 1 LAST HDL_TAP TRUE
J 0
(-3125 3875);
DISPLAY 0.872340 (-3125 3875);
DISPLAY INVISIBLE (-3125 3875);
FORCEPROP 1 LAST PATH I212
J 0
(-3452 4000);
DISPLAY 0.872340 (-3452 4000);
PAINT GREEN (-3452 4000);
DISPLAY INVISIBLE (-3452 4000);
FORCEADD TAP..1
(-3450 3900);
FORCEPROP 3 LASTPIN (-3500 3900) SIG_NAME M_I_CPU0_SA_DQS_DP<3>
J 0
(-3490 3910);
DISPLAY 0.659574 (-3490 3910);
PAINT MONO (-3490 3910);
DISPLAY INVISIBLE (-3490 3910);
FORCEPROP 1 LASTPIN (-3500 3900) BN 3
J 0
(-3512 3908);
DISPLAY 0.489362 (-3512 3908);
PAINT GREEN (-3512 3908);
FORCEPROP 2 LAST CDS_LIB mstr_standard
J 0
(-3450 3900);
DISPLAY 0.723404 (-3450 3900);
PAINT MONO (-3450 3900);
DISPLAY INVISIBLE (-3450 3900);
FORCEPROP 1 LAST BODY_TYPE PLUMBING
J 0
(-3450 3950);
DISPLAY 0.872340 (-3450 3950);
PAINT GREEN (-3450 3950);
DISPLAY INVISIBLE (-3450 3950);
FORCEPROP 1 LAST HDL_TAP TRUE
J 0
(-3125 3775);
DISPLAY 0.872340 (-3125 3775);
DISPLAY INVISIBLE (-3125 3775);
FORCEPROP 1 LAST PATH I213
J 0
(-3452 3900);
DISPLAY 0.872340 (-3452 3900);
PAINT GREEN (-3452 3900);
DISPLAY INVISIBLE (-3452 3900);
FORCEADD TAP..1
(-3450 3700);
FORCEPROP 3 LASTPIN (-3500 3700) SIG_NAME M_I_CPU0_SA_DQS_DP<1>
J 0
(-3490 3710);
DISPLAY 0.659574 (-3490 3710);
PAINT MONO (-3490 3710);
DISPLAY INVISIBLE (-3490 3710);
FORCEPROP 1 LASTPIN (-3500 3700) BN 1
J 0
(-3512 3708);
DISPLAY 0.489362 (-3512 3708);
PAINT GREEN (-3512 3708);
FORCEPROP 2 LAST CDS_LIB mstr_standard
J 0
(-3450 3700);
DISPLAY 0.723404 (-3450 3700);
PAINT MONO (-3450 3700);
DISPLAY INVISIBLE (-3450 3700);
FORCEPROP 1 LAST BODY_TYPE PLUMBING
J 0
(-3450 3750);
DISPLAY 0.872340 (-3450 3750);
PAINT GREEN (-3450 3750);
DISPLAY INVISIBLE (-3450 3750);
FORCEPROP 1 LAST HDL_TAP TRUE
J 0
(-3125 3575);
DISPLAY 0.872340 (-3125 3575);
DISPLAY INVISIBLE (-3125 3575);
FORCEPROP 1 LAST PATH I214
J 0
(-3452 3700);
DISPLAY 0.872340 (-3452 3700);
PAINT GREEN (-3452 3700);
DISPLAY INVISIBLE (-3452 3700);
FORCEADD TAP..1
(-3450 3800);
FORCEPROP 3 LASTPIN (-3500 3800) SIG_NAME M_I_CPU0_SA_DQS_DP<2>
J 0
(-3490 3810);
DISPLAY 0.659574 (-3490 3810);
PAINT MONO (-3490 3810);
DISPLAY INVISIBLE (-3490 3810);
FORCEPROP 1 LASTPIN (-3500 3800) BN 2
J 0
(-3512 3808);
DISPLAY 0.489362 (-3512 3808);
PAINT GREEN (-3512 3808);
FORCEPROP 2 LAST CDS_LIB mstr_standard
J 0
(-3450 3800);
DISPLAY 0.723404 (-3450 3800);
PAINT MONO (-3450 3800);
DISPLAY INVISIBLE (-3450 3800);
FORCEPROP 1 LAST BODY_TYPE PLUMBING
J 0
(-3450 3850);
DISPLAY 0.872340 (-3450 3850);
PAINT GREEN (-3450 3850);
DISPLAY INVISIBLE (-3450 3850);
FORCEPROP 1 LAST HDL_TAP TRUE
J 0
(-3125 3675);
DISPLAY 0.872340 (-3125 3675);
DISPLAY INVISIBLE (-3125 3675);
FORCEPROP 1 LAST PATH I215
J 0
(-3452 3800);
DISPLAY 0.872340 (-3452 3800);
PAINT GREEN (-3452 3800);
DISPLAY INVISIBLE (-3452 3800);
FORCEADD TAP..1
(-3450 3600);
FORCEPROP 3 LASTPIN (-3500 3600) SIG_NAME M_I_CPU0_SA_DQS_DP<0>
J 0
(-3490 3610);
DISPLAY 0.659574 (-3490 3610);
PAINT MONO (-3490 3610);
DISPLAY INVISIBLE (-3490 3610);
FORCEPROP 1 LASTPIN (-3500 3600) BN 0
J 0
(-3512 3608);
DISPLAY 0.489362 (-3512 3608);
PAINT GREEN (-3512 3608);
FORCEPROP 2 LAST CDS_LIB mstr_standard
J 0
(-3450 3600);
DISPLAY 0.723404 (-3450 3600);
PAINT MONO (-3450 3600);
DISPLAY INVISIBLE (-3450 3600);
FORCEPROP 1 LAST BODY_TYPE PLUMBING
J 0
(-3450 3650);
DISPLAY 0.872340 (-3450 3650);
PAINT GREEN (-3450 3650);
DISPLAY INVISIBLE (-3450 3650);
FORCEPROP 1 LAST HDL_TAP TRUE
J 0
(-3125 3475);
DISPLAY 0.872340 (-3125 3475);
DISPLAY INVISIBLE (-3125 3475);
FORCEPROP 1 LAST PATH I216
J 0
(-3452 3600);
DISPLAY 0.872340 (-3452 3600);
PAINT GREEN (-3452 3600);
DISPLAY INVISIBLE (-3452 3600);
FORCEADD TAP..1
(-3450 3350);
FORCEPROP 3 LASTPIN (-3500 3350) SIG_NAME M_I_CPU0_SB_DQS_DP<8>
J 0
(-3490 3360);
DISPLAY 0.659574 (-3490 3360);
PAINT MONO (-3490 3360);
DISPLAY INVISIBLE (-3490 3360);
FORCEPROP 1 LASTPIN (-3500 3350) BN 8
J 0
(-3512 3358);
DISPLAY 0.489362 (-3512 3358);
PAINT GREEN (-3512 3358);
FORCEPROP 2 LAST CDS_LIB mstr_standard
J 0
(-3450 3350);
DISPLAY 0.723404 (-3450 3350);
PAINT MONO (-3450 3350);
DISPLAY INVISIBLE (-3450 3350);
FORCEPROP 1 LAST BODY_TYPE PLUMBING
J 0
(-3450 3400);
DISPLAY 0.872340 (-3450 3400);
PAINT GREEN (-3450 3400);
DISPLAY INVISIBLE (-3450 3400);
FORCEPROP 1 LAST HDL_TAP TRUE
J 0
(-3125 3225);
DISPLAY 0.872340 (-3125 3225);
DISPLAY INVISIBLE (-3125 3225);
FORCEPROP 1 LAST PATH I217
J 0
(-3452 3350);
DISPLAY 0.872340 (-3452 3350);
PAINT GREEN (-3452 3350);
DISPLAY INVISIBLE (-3452 3350);
FORCEADD TAP..1
(-3450 3450);
FORCEPROP 3 LASTPIN (-3500 3450) SIG_NAME M_I_CPU0_SB_DQS_DP<9>
J 0
(-3490 3460);
DISPLAY 0.659574 (-3490 3460);
PAINT MONO (-3490 3460);
DISPLAY INVISIBLE (-3490 3460);
FORCEPROP 1 LASTPIN (-3500 3450) BN 9
J 0
(-3512 3458);
DISPLAY 0.489362 (-3512 3458);
PAINT GREEN (-3512 3458);
FORCEPROP 2 LAST CDS_LIB mstr_standard
J 0
(-3450 3450);
DISPLAY 0.723404 (-3450 3450);
PAINT MONO (-3450 3450);
DISPLAY INVISIBLE (-3450 3450);
FORCEPROP 1 LAST BODY_TYPE PLUMBING
J 0
(-3450 3500);
DISPLAY 0.872340 (-3450 3500);
PAINT GREEN (-3450 3500);
DISPLAY INVISIBLE (-3450 3500);
FORCEPROP 1 LAST HDL_TAP TRUE
J 0
(-3125 3325);
DISPLAY 0.872340 (-3125 3325);
DISPLAY INVISIBLE (-3125 3325);
FORCEPROP 1 LAST PATH I218
J 0
(-3452 3450);
DISPLAY 0.872340 (-3452 3450);
PAINT GREEN (-3452 3450);
DISPLAY INVISIBLE (-3452 3450);
FORCEADD TAP..1
(-3250 3300);
FORCEPROP 3 LASTPIN (-3300 3300) SIG_NAME M_I_CPU0_SB_DQS_DN<8>
J 0
(-3290 3310);
DISPLAY 0.659574 (-3290 3310);
PAINT MONO (-3290 3310);
DISPLAY INVISIBLE (-3290 3310);
FORCEPROP 1 LASTPIN (-3300 3300) BN 8
J 0
(-3312 3308);
DISPLAY 0.489362 (-3312 3308);
PAINT GREEN (-3312 3308);
FORCEPROP 2 LAST CDS_LIB mstr_standard
J 0
(-3250 3300);
DISPLAY 0.723404 (-3250 3300);
PAINT MONO (-3250 3300);
DISPLAY INVISIBLE (-3250 3300);
FORCEPROP 1 LAST BODY_TYPE PLUMBING
J 0
(-3250 3350);
DISPLAY 0.872340 (-3250 3350);
PAINT GREEN (-3250 3350);
DISPLAY INVISIBLE (-3250 3350);
FORCEPROP 1 LAST HDL_TAP TRUE
J 0
(-2925 3175);
DISPLAY 0.872340 (-2925 3175);
DISPLAY INVISIBLE (-2925 3175);
FORCEPROP 1 LAST PATH I219
J 0
(-3252 3300);
DISPLAY 0.872340 (-3252 3300);
PAINT GREEN (-3252 3300);
DISPLAY INVISIBLE (-3252 3300);
FORCEADD SCONN288_DDR506112002KQ..1
(-6850 3700);
FORCEPROP 1 LAST LOCATION J18
J 0
(-7300 5775);
DISPLAY 0.468085 (-7300 5775);
PAINT SKYBLUE (-7300 5775);
FORCEPROP 0 LAST $SEC 1
J 0
(-7300 5925);
DISPLAY 0.680851 (-7300 5925);
PAINT MONO (-7300 5925);
DISPLAY INVISIBLE (-7300 5925);
FORCEPROP 2 LAST CDS_SEC 1
J 0
(-7300 5925);
DISPLAY 1.021277 (-7300 5925);
DISPLAY INVISIBLE (-7300 5925);
FORCEPROP 0 LASTPIN (-7450 3100) $PN 62
J 2
(-7460 3110);
DISPLAY 0.680851 (-7460 3110);
PAINT MONO (-7460 3110);
FORCEPROP 0 LASTPIN (-7450 5150) $PN 66
J 2
(-7460 5160);
DISPLAY 0.680851 (-7460 5160);
PAINT MONO (-7460 5160);
FORCEPROP 0 LASTPIN (-7450 4750) $PN 76
J 2
(-7460 4760);
DISPLAY 0.680851 (-7460 4760);
PAINT MONO (-7460 4760);
FORCEPROP 0 LASTPIN (-7450 5200) $PN 211
J 2
(-7460 5210);
DISPLAY 0.680851 (-7460 5210);
PAINT MONO (-7460 5210);
FORCEPROP 0 LASTPIN (-7450 4800) $PN 221
J 2
(-7460 4810);
DISPLAY 0.680851 (-7460 4810);
PAINT MONO (-7460 4810);
FORCEPROP 0 LASTPIN (-7450 5250) $PN 68
J 2
(-7460 5260);
DISPLAY 0.680851 (-7460 5260);
PAINT MONO (-7460 5260);
FORCEPROP 0 LASTPIN (-7450 4850) $PN 78
J 2
(-7460 4860);
DISPLAY 0.680851 (-7460 4860);
PAINT MONO (-7460 4860);
FORCEPROP 0 LASTPIN (-7450 5300) $PN 213
J 2
(-7460 5310);
DISPLAY 0.680851 (-7460 5310);
PAINT MONO (-7460 5310);
FORCEPROP 0 LASTPIN (-7450 4900) $PN 223
J 2
(-7460 4910);
DISPLAY 0.680851 (-7460 4910);
PAINT MONO (-7460 4910);
FORCEPROP 0 LASTPIN (-7450 5350) $PN 70
J 2
(-7460 5360);
DISPLAY 0.680851 (-7460 5360);
PAINT MONO (-7460 5360);
FORCEPROP 0 LASTPIN (-7450 4950) $PN 80
J 2
(-7460 4960);
DISPLAY 0.680851 (-7460 4960);
PAINT MONO (-7460 4960);
FORCEPROP 0 LASTPIN (-7450 5400) $PN 215
J 2
(-7460 5410);
DISPLAY 0.680851 (-7460 5410);
PAINT MONO (-7460 5410);
FORCEPROP 0 LASTPIN (-7450 5000) $PN 225
J 2
(-7460 5010);
DISPLAY 0.680851 (-7460 5010);
PAINT MONO (-7460 5010);
FORCEPROP 0 LASTPIN (-7450 5450) $PN 72
J 2
(-7460 5460);
DISPLAY 0.680851 (-7460 5460);
PAINT MONO (-7460 5460);
FORCEPROP 0 LASTPIN (-7450 5050) $PN 82
J 2
(-7460 5060);
DISPLAY 0.680851 (-7460 5060);
PAINT MONO (-7460 5060);
FORCEPROP 0 LASTPIN (-7450 3700) $PN 51
J 2
(-7460 3710);
DISPLAY 0.680851 (-7460 3710);
PAINT MONO (-7460 3710);
FORCEPROP 0 LASTPIN (-7450 3250) $PN 96
J 2
(-7460 3260);
DISPLAY 0.680851 (-7460 3260);
PAINT MONO (-7460 3260);
FORCEPROP 0 LASTPIN (-7450 3750) $PN 53
J 2
(-7460 3760);
DISPLAY 0.680851 (-7460 3760);
PAINT MONO (-7460 3760);
FORCEPROP 0 LASTPIN (-7450 3300) $PN 98
J 2
(-7460 3310);
DISPLAY 0.680851 (-7460 3310);
PAINT MONO (-7460 3310);
FORCEPROP 0 LASTPIN (-7450 3800) $PN 196
J 2
(-7460 3810);
DISPLAY 0.680851 (-7460 3810);
PAINT MONO (-7460 3810);
FORCEPROP 0 LASTPIN (-7450 3350) $PN 241
J 2
(-7460 3360);
DISPLAY 0.680851 (-7460 3360);
PAINT MONO (-7460 3360);
FORCEPROP 0 LASTPIN (-7450 3850) $PN 198
J 2
(-7460 3860);
DISPLAY 0.680851 (-7460 3860);
PAINT MONO (-7460 3860);
FORCEPROP 0 LASTPIN (-7450 3400) $PN 243
J 2
(-7460 3410);
DISPLAY 0.680851 (-7460 3410);
PAINT MONO (-7460 3410);
FORCEPROP 0 LASTPIN (-7450 3900) $PN 58
J 2
(-7460 3910);
DISPLAY 0.680851 (-7460 3910);
PAINT MONO (-7460 3910);
FORCEPROP 0 LASTPIN (-7450 3450) $PN 89
J 2
(-7460 3460);
DISPLAY 0.680851 (-7460 3460);
PAINT MONO (-7460 3460);
FORCEPROP 0 LASTPIN (-7450 3950) $PN 60
J 2
(-7460 3960);
DISPLAY 0.680851 (-7460 3960);
PAINT MONO (-7460 3960);
FORCEPROP 0 LASTPIN (-7450 3500) $PN 91
J 2
(-7460 3510);
DISPLAY 0.680851 (-7460 3510);
PAINT MONO (-7460 3510);
FORCEPROP 0 LASTPIN (-7450 4000) $PN 203
J 2
(-7460 4010);
DISPLAY 0.680851 (-7460 4010);
PAINT MONO (-7460 4010);
FORCEPROP 0 LASTPIN (-7450 3550) $PN 234
J 2
(-7460 3560);
DISPLAY 0.680851 (-7460 3560);
PAINT MONO (-7460 3560);
FORCEPROP 0 LASTPIN (-7450 4050) $PN 205
J 2
(-7460 4060);
DISPLAY 0.680851 (-7460 4060);
PAINT MONO (-7460 4060);
FORCEPROP 0 LASTPIN (-7450 3600) $PN 236
J 2
(-7460 3610);
DISPLAY 0.680851 (-7460 3610);
PAINT MONO (-7460 3610);
FORCEPROP 0 LASTPIN (-7450 4150) $PN 218
J 2
(-7460 4160);
DISPLAY 0.680851 (-7460 4160);
PAINT MONO (-7460 4160);
FORCEPROP 0 LASTPIN (-7450 4200) $PN 217
J 2
(-7460 4210);
DISPLAY 0.680851 (-7460 4210);
PAINT MONO (-7460 4210);
FORCEPROP 0 LASTPIN (-7450 4450) $PN 64
J 2
(-7460 4460);
DISPLAY 0.680851 (-7460 4460);
PAINT MONO (-7460 4460);
FORCEPROP 0 LASTPIN (-7450 4300) $PN 84
J 2
(-7460 4310);
DISPLAY 0.680851 (-7460 4310);
PAINT MONO (-7460 4310);
FORCEPROP 0 LASTPIN (-7450 4500) $PN 209
J 2
(-7460 4510);
DISPLAY 0.680851 (-7460 4510);
PAINT MONO (-7460 4510);
FORCEPROP 0 LASTPIN (-7450 4350) $PN 229
J 2
(-7460 4360);
DISPLAY 0.680851 (-7460 4360);
PAINT MONO (-7460 4360);
FORCEPROP 0 LASTPIN (-6250 3900) $PN 7
J 0
(-6240 3910);
DISPLAY 0.680851 (-6240 3910);
PAINT MONO (-6240 3910);
FORCEPROP 0 LASTPIN (-6250 2250) $PN 100
J 0
(-6240 2260);
DISPLAY 0.680851 (-6240 2260);
PAINT MONO (-6240 2260);
FORCEPROP 0 LASTPIN (-6250 3950) $PN 9
J 0
(-6240 3960);
DISPLAY 0.680851 (-6240 3960);
PAINT MONO (-6240 3960);
FORCEPROP 0 LASTPIN (-6250 2300) $PN 102
J 0
(-6240 2310);
DISPLAY 0.680851 (-6240 2310);
PAINT MONO (-6240 2310);
FORCEPROP 0 LASTPIN (-6250 4000) $PN 152
J 0
(-6240 4010);
DISPLAY 0.680851 (-6240 4010);
PAINT MONO (-6240 4010);
FORCEPROP 0 LASTPIN (-6250 2350) $PN 245
J 0
(-6240 2360);
DISPLAY 0.680851 (-6240 2360);
PAINT MONO (-6240 2360);
FORCEPROP 0 LASTPIN (-6250 4050) $PN 154
J 0
(-6240 4060);
DISPLAY 0.680851 (-6240 4060);
PAINT MONO (-6240 4060);
FORCEPROP 0 LASTPIN (-6250 2400) $PN 247
J 0
(-6240 2410);
DISPLAY 0.680851 (-6240 2410);
PAINT MONO (-6240 2410);
FORCEPROP 0 LASTPIN (-6250 4100) $PN 14
J 0
(-6240 4110);
DISPLAY 0.680851 (-6240 4110);
PAINT MONO (-6240 4110);
FORCEPROP 0 LASTPIN (-6250 2450) $PN 107
J 0
(-6240 2460);
DISPLAY 0.680851 (-6240 2460);
PAINT MONO (-6240 2460);
FORCEPROP 0 LASTPIN (-6250 4150) $PN 16
J 0
(-6240 4160);
DISPLAY 0.680851 (-6240 4160);
PAINT MONO (-6240 4160);
FORCEPROP 0 LASTPIN (-6250 2500) $PN 109
J 0
(-6240 2510);
DISPLAY 0.680851 (-6240 2510);
PAINT MONO (-6240 2510);
FORCEPROP 0 LASTPIN (-6250 4200) $PN 159
J 0
(-6240 4210);
DISPLAY 0.680851 (-6240 4210);
PAINT MONO (-6240 4210);
FORCEPROP 0 LASTPIN (-6250 2550) $PN 252
J 0
(-6240 2560);
DISPLAY 0.680851 (-6240 2560);
PAINT MONO (-6240 2560);
FORCEPROP 0 LASTPIN (-6250 4250) $PN 161
J 0
(-6240 4260);
DISPLAY 0.680851 (-6240 4260);
PAINT MONO (-6240 4260);
FORCEPROP 0 LASTPIN (-6250 2600) $PN 254
J 0
(-6240 2610);
DISPLAY 0.680851 (-6240 2610);
PAINT MONO (-6240 2610);
FORCEPROP 0 LASTPIN (-6250 4300) $PN 18
J 0
(-6240 4310);
DISPLAY 0.680851 (-6240 4310);
PAINT MONO (-6240 4310);
FORCEPROP 0 LASTPIN (-6250 2650) $PN 111
J 0
(-6240 2660);
DISPLAY 0.680851 (-6240 2660);
PAINT MONO (-6240 2660);
FORCEPROP 0 LASTPIN (-6250 4350) $PN 20
J 0
(-6240 4360);
DISPLAY 0.680851 (-6240 4360);
PAINT MONO (-6240 4360);
FORCEPROP 0 LASTPIN (-6250 2700) $PN 113
J 0
(-6240 2710);
DISPLAY 0.680851 (-6240 2710);
PAINT MONO (-6240 2710);
FORCEPROP 0 LASTPIN (-6250 4400) $PN 163
J 0
(-6240 4410);
DISPLAY 0.680851 (-6240 4410);
PAINT MONO (-6240 4410);
FORCEPROP 0 LASTPIN (-6250 2750) $PN 256
J 0
(-6240 2760);
DISPLAY 0.680851 (-6240 2760);
PAINT MONO (-6240 2760);
FORCEPROP 0 LASTPIN (-6250 4450) $PN 165
J 0
(-6240 4460);
DISPLAY 0.680851 (-6240 4460);
PAINT MONO (-6240 4460);
FORCEPROP 0 LASTPIN (-6250 2800) $PN 258
J 0
(-6240 2810);
DISPLAY 0.680851 (-6240 2810);
PAINT MONO (-6240 2810);
FORCEPROP 0 LASTPIN (-6250 4500) $PN 25
J 0
(-6240 4510);
DISPLAY 0.680851 (-6240 4510);
PAINT MONO (-6240 4510);
FORCEPROP 0 LASTPIN (-6250 2850) $PN 118
J 0
(-6240 2860);
DISPLAY 0.680851 (-6240 2860);
PAINT MONO (-6240 2860);
FORCEPROP 0 LASTPIN (-6250 4550) $PN 27
J 0
(-6240 4560);
DISPLAY 0.680851 (-6240 4560);
PAINT MONO (-6240 4560);
FORCEPROP 0 LASTPIN (-6250 2900) $PN 120
J 0
(-6240 2910);
DISPLAY 0.680851 (-6240 2910);
PAINT MONO (-6240 2910);
FORCEPROP 0 LASTPIN (-6250 4600) $PN 170
J 0
(-6240 4610);
DISPLAY 0.680851 (-6240 4610);
PAINT MONO (-6240 4610);
FORCEPROP 0 LASTPIN (-6250 2950) $PN 263
J 0
(-6240 2960);
DISPLAY 0.680851 (-6240 2960);
PAINT MONO (-6240 2960);
FORCEPROP 0 LASTPIN (-6250 4650) $PN 172
J 0
(-6240 4660);
DISPLAY 0.680851 (-6240 4660);
PAINT MONO (-6240 4660);
FORCEPROP 0 LASTPIN (-6250 3000) $PN 265
J 0
(-6240 3010);
DISPLAY 0.680851 (-6240 3010);
PAINT MONO (-6240 3010);
FORCEPROP 0 LASTPIN (-6250 4700) $PN 29
J 0
(-6240 4710);
DISPLAY 0.680851 (-6240 4710);
PAINT MONO (-6240 4710);
FORCEPROP 0 LASTPIN (-6250 3050) $PN 122
J 0
(-6240 3060);
DISPLAY 0.680851 (-6240 3060);
PAINT MONO (-6240 3060);
FORCEPROP 0 LASTPIN (-6250 4750) $PN 31
J 0
(-6240 4760);
DISPLAY 0.680851 (-6240 4760);
PAINT MONO (-6240 4760);
FORCEPROP 0 LASTPIN (-6250 3100) $PN 124
J 0
(-6240 3110);
DISPLAY 0.680851 (-6240 3110);
PAINT MONO (-6240 3110);
FORCEPROP 0 LASTPIN (-6250 4800) $PN 174
J 0
(-6240 4810);
DISPLAY 0.680851 (-6240 4810);
PAINT MONO (-6240 4810);
FORCEPROP 0 LASTPIN (-6250 3150) $PN 267
J 0
(-6240 3160);
DISPLAY 0.680851 (-6240 3160);
PAINT MONO (-6240 3160);
FORCEPROP 0 LASTPIN (-6250 4850) $PN 176
J 0
(-6240 4860);
DISPLAY 0.680851 (-6240 4860);
PAINT MONO (-6240 4860);
FORCEPROP 0 LASTPIN (-6250 3200) $PN 269
J 0
(-6240 3210);
DISPLAY 0.680851 (-6240 3210);
PAINT MONO (-6240 3210);
FORCEPROP 0 LASTPIN (-6250 4900) $PN 36
J 0
(-6240 4910);
DISPLAY 0.680851 (-6240 4910);
PAINT MONO (-6240 4910);
FORCEPROP 0 LASTPIN (-6250 3250) $PN 129
J 0
(-6240 3260);
DISPLAY 0.680851 (-6240 3260);
PAINT MONO (-6240 3260);
FORCEPROP 0 LASTPIN (-6250 4950) $PN 38
J 0
(-6240 4960);
DISPLAY 0.680851 (-6240 4960);
PAINT MONO (-6240 4960);
FORCEPROP 0 LASTPIN (-6250 3300) $PN 131
J 0
(-6240 3310);
DISPLAY 0.680851 (-6240 3310);
PAINT MONO (-6240 3310);
FORCEPROP 0 LASTPIN (-6250 5000) $PN 181
J 0
(-6240 5010);
DISPLAY 0.680851 (-6240 5010);
PAINT MONO (-6240 5010);
FORCEPROP 0 LASTPIN (-6250 3350) $PN 274
J 0
(-6240 3360);
DISPLAY 0.680851 (-6240 3360);
PAINT MONO (-6240 3360);
FORCEPROP 0 LASTPIN (-6250 5050) $PN 183
J 0
(-6240 5060);
DISPLAY 0.680851 (-6240 5060);
PAINT MONO (-6240 5060);
FORCEPROP 0 LASTPIN (-6250 3400) $PN 276
J 0
(-6240 3410);
DISPLAY 0.680851 (-6240 3410);
PAINT MONO (-6240 3410);
FORCEPROP 0 LASTPIN (-6250 5100) $PN 40
J 0
(-6240 5110);
DISPLAY 0.680851 (-6240 5110);
PAINT MONO (-6240 5110);
FORCEPROP 0 LASTPIN (-6250 3450) $PN 133
J 0
(-6240 3460);
DISPLAY 0.680851 (-6240 3460);
PAINT MONO (-6240 3460);
FORCEPROP 0 LASTPIN (-6250 5150) $PN 42
J 0
(-6240 5160);
DISPLAY 0.680851 (-6240 5160);
PAINT MONO (-6240 5160);
FORCEPROP 0 LASTPIN (-6250 3500) $PN 135
J 0
(-6240 3510);
DISPLAY 0.680851 (-6240 3510);
PAINT MONO (-6240 3510);
FORCEPROP 0 LASTPIN (-6250 5200) $PN 185
J 0
(-6240 5210);
DISPLAY 0.680851 (-6240 5210);
PAINT MONO (-6240 5210);
FORCEPROP 0 LASTPIN (-6250 3550) $PN 278
J 0
(-6240 3560);
DISPLAY 0.680851 (-6240 3560);
PAINT MONO (-6240 3560);
FORCEPROP 0 LASTPIN (-6250 5250) $PN 187
J 0
(-6240 5260);
DISPLAY 0.680851 (-6240 5260);
PAINT MONO (-6240 5260);
FORCEPROP 0 LASTPIN (-6250 3600) $PN 280
J 0
(-6240 3610);
DISPLAY 0.680851 (-6240 3610);
PAINT MONO (-6240 3610);
FORCEPROP 0 LASTPIN (-6250 5300) $PN 47
J 0
(-6240 5310);
DISPLAY 0.680851 (-6240 5310);
PAINT MONO (-6240 5310);
FORCEPROP 0 LASTPIN (-6250 3650) $PN 140
J 0
(-6240 3660);
DISPLAY 0.680851 (-6240 3660);
PAINT MONO (-6240 3660);
FORCEPROP 0 LASTPIN (-6250 5350) $PN 49
J 0
(-6240 5360);
DISPLAY 0.680851 (-6240 5360);
PAINT MONO (-6240 5360);
FORCEPROP 0 LASTPIN (-6250 3700) $PN 142
J 0
(-6240 3710);
DISPLAY 0.680851 (-6240 3710);
PAINT MONO (-6240 3710);
FORCEPROP 0 LASTPIN (-6250 5400) $PN 192
J 0
(-6240 5410);
DISPLAY 0.680851 (-6240 5410);
PAINT MONO (-6240 5410);
FORCEPROP 0 LASTPIN (-6250 3750) $PN 285
J 0
(-6240 3760);
DISPLAY 0.680851 (-6240 3760);
PAINT MONO (-6240 3760);
FORCEPROP 0 LASTPIN (-6250 5450) $PN 194
J 0
(-6240 5460);
DISPLAY 0.680851 (-6240 5460);
PAINT MONO (-6240 5460);
FORCEPROP 0 LASTPIN (-6250 3800) $PN 287
J 0
(-6240 3810);
DISPLAY 0.680851 (-6240 3810);
PAINT MONO (-6240 3810);
FORCEPROP 0 LASTPIN (-7450 2950) $PN 148
J 2
(-7460 2960);
DISPLAY 0.680851 (-7460 2960);
PAINT MONO (-7460 2960);
FORCEPROP 0 LASTPIN (-7450 2850) $PN 4
J 2
(-7460 2860);
DISPLAY 0.680851 (-7460 2860);
PAINT MONO (-7460 2860);
FORCEPROP 0 LASTPIN (-7450 2900) $PN 5
J 2
(-7460 2910);
DISPLAY 0.680851 (-7460 2910);
PAINT MONO (-7460 2910);
FORCEPROP 0 LASTPIN (-7450 2050) $PN 86
J 2
(-7460 2060);
DISPLAY 0.680851 (-7460 2060);
PAINT MONO (-7460 2060);
FORCEPROP 0 LASTPIN (-7450 2000) $PN 87
J 2
(-7460 2010);
DISPLAY 0.680851 (-7460 2010);
PAINT MONO (-7460 2010);
FORCEPROP 0 LASTPIN (-7450 4650) $PN 74
J 2
(-7460 4660);
DISPLAY 0.680851 (-7460 4660);
PAINT MONO (-7460 4660);
FORCEPROP 0 LASTPIN (-7450 4600) $PN 227
J 2
(-7460 4610);
DISPLAY 0.680851 (-7460 4610);
PAINT MONO (-7460 4610);
FORCEPROP 0 LASTPIN (-7450 2600) $PN 147
J 2
(-7460 2610);
DISPLAY 0.680851 (-7460 2610);
PAINT MONO (-7460 2610);
FORCEPROP 0 LASTPIN (-7450 3150) $PN 207
J 2
(-7460 3160);
DISPLAY 0.680851 (-7460 3160);
PAINT MONO (-7460 3160);
FORCEPROP 0 LASTPIN (-7450 2200) $PN 2
J 2
(-7460 2210);
DISPLAY 0.680851 (-7460 2210);
PAINT MONO (-7460 2210);
FORCEPROP 0 LASTPIN (-7450 2250) $PN 144
J 2
(-7460 2260);
DISPLAY 0.680851 (-7460 2260);
PAINT MONO (-7460 2260);
FORCEPROP 0 LASTPIN (-7450 2300) $PN 149
J 2
(-7460 2310);
DISPLAY 0.680851 (-7460 2310);
PAINT MONO (-7460 2310);
FORCEPROP 0 LASTPIN (-7450 2350) $PN 150
J 2
(-7460 2360);
DISPLAY 0.680851 (-7460 2360);
PAINT MONO (-7460 2360);
FORCEPROP 0 LASTPIN (-7450 2400) $PN 220
J 2
(-7460 2410);
DISPLAY 0.680851 (-7460 2410);
PAINT MONO (-7460 2410);
FORCEPROP 0 LASTPIN (-7450 2450) $PN 231
J 2
(-7460 2460);
DISPLAY 0.680851 (-7460 2460);
PAINT MONO (-7460 2460);
FORCEPROP 0 LASTPIN (-7450 2500) $PN 232
J 2
(-7460 2510);
DISPLAY 0.680851 (-7460 2510);
PAINT MONO (-7460 2510);
FORCEPROP 0 LASTPIN (-7450 3000) $PN 3
J 2
(-7460 3010);
DISPLAY 0.680851 (-7460 3010);
PAINT MONO (-7460 3010);
FORCEPROP 2 LAST PART_TYPE SMLF
J 0
(-7300 5875);
DISPLAY 1.021277 (-7300 5875);
FORCEPROP 2 LAST VALUE SCONN288_DDR506112002KQ
J 0
(-7300 5825);
DISPLAY 0.489362 (-7300 5825);
PAINT SKYBLUE (-7300 5825);
FORCEPROP 1 LAST MATERIAL IO
J 0
(-7300 5625);
DISPLAY 0.468085 (-7300 5625);
PAINT SKYBLUE (-7300 5625);
FORCEPROP 2 LAST CDS_LIB pure_quanta
J 0
(-6850 3700);
DISPLAY INVISIBLE (-6850 3700);
FORCEPROP 1 LAST NEEDS_NO_SIZE TRUE
J 0
(-6850 3700);
DISPLAY 0.723404 (-6850 3700);
PAINT GREEN (-6850 3700);
DISPLAY INVISIBLE (-6850 3700);
FORCEPROP 1 LAST CDS_LMAN_SYM_OUTLINE -450,1900,450,-1850
J 0
(-6850 3700);
DISPLAY 0.468085 (-6850 3700);
PAINT GREEN (-6850 3700);
DISPLAY INVISIBLE (-6850 3700);
FORCEPROP 1 LAST PATH I22
J 0
(-6850 3700);
DISPLAY 0.723404 (-6850 3700);
PAINT GREEN (-6850 3700);
DISPLAY INVISIBLE (-6850 3700);
FORCEPROP 1 LAST PART_NUMBER DFHST8FS479
J 0
(-7300 5700);
DISPLAY 0.468085 (-7300 5700);
PAINT SKYBLUE (-7300 5700);
DISPLAY INVISIBLE (-7300 5700);
FORCEADD TAP..1
(-3250 3200);
FORCEPROP 3 LASTPIN (-3300 3200) SIG_NAME M_I_CPU0_SB_DQS_DN<7>
J 0
(-3290 3210);
DISPLAY 0.659574 (-3290 3210);
PAINT MONO (-3290 3210);
DISPLAY INVISIBLE (-3290 3210);
FORCEPROP 1 LASTPIN (-3300 3200) BN 7
J 0
(-3312 3208);
DISPLAY 0.489362 (-3312 3208);
PAINT GREEN (-3312 3208);
FORCEPROP 2 LAST CDS_LIB mstr_standard
J 0
(-3250 3200);
DISPLAY 0.723404 (-3250 3200);
PAINT MONO (-3250 3200);
DISPLAY INVISIBLE (-3250 3200);
FORCEPROP 1 LAST BODY_TYPE PLUMBING
J 0
(-3250 3250);
DISPLAY 0.872340 (-3250 3250);
PAINT GREEN (-3250 3250);
DISPLAY INVISIBLE (-3250 3250);
FORCEPROP 1 LAST HDL_TAP TRUE
J 0
(-2925 3075);
DISPLAY 0.872340 (-2925 3075);
DISPLAY INVISIBLE (-2925 3075);
FORCEPROP 1 LAST PATH I220
J 0
(-3252 3200);
DISPLAY 0.872340 (-3252 3200);
PAINT GREEN (-3252 3200);
DISPLAY INVISIBLE (-3252 3200);
FORCEADD TAP..1
(-3250 3100);
FORCEPROP 3 LASTPIN (-3300 3100) SIG_NAME M_I_CPU0_SB_DQS_DN<6>
J 0
(-3290 3110);
DISPLAY 0.659574 (-3290 3110);
PAINT MONO (-3290 3110);
DISPLAY INVISIBLE (-3290 3110);
FORCEPROP 1 LASTPIN (-3300 3100) BN 6
J 0
(-3312 3108);
DISPLAY 0.489362 (-3312 3108);
PAINT GREEN (-3312 3108);
FORCEPROP 2 LAST CDS_LIB mstr_standard
J 0
(-3250 3100);
DISPLAY 0.723404 (-3250 3100);
PAINT MONO (-3250 3100);
DISPLAY INVISIBLE (-3250 3100);
FORCEPROP 1 LAST BODY_TYPE PLUMBING
J 0
(-3250 3150);
DISPLAY 0.872340 (-3250 3150);
PAINT GREEN (-3250 3150);
DISPLAY INVISIBLE (-3250 3150);
FORCEPROP 1 LAST HDL_TAP TRUE
J 0
(-2925 2975);
DISPLAY 0.872340 (-2925 2975);
DISPLAY INVISIBLE (-2925 2975);
FORCEPROP 1 LAST PATH I221
J 0
(-3252 3100);
DISPLAY 0.872340 (-3252 3100);
PAINT GREEN (-3252 3100);
DISPLAY INVISIBLE (-3252 3100);
FORCEADD TAP..1
(-3250 3000);
FORCEPROP 3 LASTPIN (-3300 3000) SIG_NAME M_I_CPU0_SB_DQS_DN<5>
J 0
(-3290 3010);
DISPLAY 0.659574 (-3290 3010);
PAINT MONO (-3290 3010);
DISPLAY INVISIBLE (-3290 3010);
FORCEPROP 1 LASTPIN (-3300 3000) BN 5
J 0
(-3312 3008);
DISPLAY 0.489362 (-3312 3008);
PAINT GREEN (-3312 3008);
FORCEPROP 2 LAST CDS_LIB mstr_standard
J 0
(-3250 3000);
DISPLAY 0.723404 (-3250 3000);
PAINT MONO (-3250 3000);
DISPLAY INVISIBLE (-3250 3000);
FORCEPROP 1 LAST BODY_TYPE PLUMBING
J 0
(-3250 3050);
DISPLAY 0.872340 (-3250 3050);
PAINT GREEN (-3250 3050);
DISPLAY INVISIBLE (-3250 3050);
FORCEPROP 1 LAST HDL_TAP TRUE
J 0
(-2925 2875);
DISPLAY 0.872340 (-2925 2875);
DISPLAY INVISIBLE (-2925 2875);
FORCEPROP 1 LAST PATH I222
J 0
(-3252 3000);
DISPLAY 0.872340 (-3252 3000);
PAINT GREEN (-3252 3000);
DISPLAY INVISIBLE (-3252 3000);
FORCEADD TAP..1
(-3250 2900);
FORCEPROP 3 LASTPIN (-3300 2900) SIG_NAME M_I_CPU0_SB_DQS_DN<4>
J 0
(-3290 2910);
DISPLAY 0.659574 (-3290 2910);
PAINT MONO (-3290 2910);
DISPLAY INVISIBLE (-3290 2910);
FORCEPROP 1 LASTPIN (-3300 2900) BN 4
J 0
(-3312 2908);
DISPLAY 0.489362 (-3312 2908);
PAINT GREEN (-3312 2908);
FORCEPROP 2 LAST CDS_LIB mstr_standard
J 0
(-3250 2900);
DISPLAY 0.723404 (-3250 2900);
PAINT MONO (-3250 2900);
DISPLAY INVISIBLE (-3250 2900);
FORCEPROP 1 LAST BODY_TYPE PLUMBING
J 0
(-3250 2950);
DISPLAY 0.872340 (-3250 2950);
PAINT GREEN (-3250 2950);
DISPLAY INVISIBLE (-3250 2950);
FORCEPROP 1 LAST HDL_TAP TRUE
J 0
(-2925 2775);
DISPLAY 0.872340 (-2925 2775);
DISPLAY INVISIBLE (-2925 2775);
FORCEPROP 1 LAST PATH I223
J 0
(-3252 2900);
DISPLAY 0.872340 (-3252 2900);
PAINT GREEN (-3252 2900);
DISPLAY INVISIBLE (-3252 2900);
FORCEADD TAP..1
(-3250 2800);
FORCEPROP 3 LASTPIN (-3300 2800) SIG_NAME M_I_CPU0_SB_DQS_DN<3>
J 0
(-3290 2810);
DISPLAY 0.659574 (-3290 2810);
PAINT MONO (-3290 2810);
DISPLAY INVISIBLE (-3290 2810);
FORCEPROP 1 LASTPIN (-3300 2800) BN 3
J 0
(-3312 2808);
DISPLAY 0.489362 (-3312 2808);
PAINT GREEN (-3312 2808);
FORCEPROP 2 LAST CDS_LIB mstr_standard
J 0
(-3250 2800);
DISPLAY 0.723404 (-3250 2800);
PAINT MONO (-3250 2800);
DISPLAY INVISIBLE (-3250 2800);
FORCEPROP 1 LAST BODY_TYPE PLUMBING
J 0
(-3250 2850);
DISPLAY 0.872340 (-3250 2850);
PAINT GREEN (-3250 2850);
DISPLAY INVISIBLE (-3250 2850);
FORCEPROP 1 LAST HDL_TAP TRUE
J 0
(-2925 2675);
DISPLAY 0.872340 (-2925 2675);
DISPLAY INVISIBLE (-2925 2675);
FORCEPROP 1 LAST PATH I224
J 0
(-3252 2800);
DISPLAY 0.872340 (-3252 2800);
PAINT GREEN (-3252 2800);
DISPLAY INVISIBLE (-3252 2800);
FORCEADD TAP..1
(-3250 2700);
FORCEPROP 3 LASTPIN (-3300 2700) SIG_NAME M_I_CPU0_SB_DQS_DN<2>
J 0
(-3290 2710);
DISPLAY 0.659574 (-3290 2710);
PAINT MONO (-3290 2710);
DISPLAY INVISIBLE (-3290 2710);
FORCEPROP 1 LASTPIN (-3300 2700) BN 2
J 0
(-3312 2708);
DISPLAY 0.489362 (-3312 2708);
PAINT GREEN (-3312 2708);
FORCEPROP 2 LAST CDS_LIB mstr_standard
J 0
(-3250 2700);
DISPLAY 0.723404 (-3250 2700);
PAINT MONO (-3250 2700);
DISPLAY INVISIBLE (-3250 2700);
FORCEPROP 1 LAST BODY_TYPE PLUMBING
J 0
(-3250 2750);
DISPLAY 0.872340 (-3250 2750);
PAINT GREEN (-3250 2750);
DISPLAY INVISIBLE (-3250 2750);
FORCEPROP 1 LAST HDL_TAP TRUE
J 0
(-2925 2575);
DISPLAY 0.872340 (-2925 2575);
DISPLAY INVISIBLE (-2925 2575);
FORCEPROP 1 LAST PATH I225
J 0
(-3252 2700);
DISPLAY 0.872340 (-3252 2700);
PAINT GREEN (-3252 2700);
DISPLAY INVISIBLE (-3252 2700);
FORCEADD TAP..1
(-3250 2600);
FORCEPROP 3 LASTPIN (-3300 2600) SIG_NAME M_I_CPU0_SB_DQS_DN<1>
J 0
(-3290 2610);
DISPLAY 0.659574 (-3290 2610);
PAINT MONO (-3290 2610);
DISPLAY INVISIBLE (-3290 2610);
FORCEPROP 1 LASTPIN (-3300 2600) BN 1
J 0
(-3312 2608);
DISPLAY 0.489362 (-3312 2608);
PAINT GREEN (-3312 2608);
FORCEPROP 2 LAST CDS_LIB mstr_standard
J 0
(-3250 2600);
DISPLAY 0.723404 (-3250 2600);
PAINT MONO (-3250 2600);
DISPLAY INVISIBLE (-3250 2600);
FORCEPROP 1 LAST BODY_TYPE PLUMBING
J 0
(-3250 2650);
DISPLAY 0.872340 (-3250 2650);
PAINT GREEN (-3250 2650);
DISPLAY INVISIBLE (-3250 2650);
FORCEPROP 1 LAST HDL_TAP TRUE
J 0
(-2925 2475);
DISPLAY 0.872340 (-2925 2475);
DISPLAY INVISIBLE (-2925 2475);
FORCEPROP 1 LAST PATH I226
J 0
(-3252 2600);
DISPLAY 0.872340 (-3252 2600);
PAINT GREEN (-3252 2600);
DISPLAY INVISIBLE (-3252 2600);
FORCEADD TAP..1
(-3250 2500);
FORCEPROP 3 LASTPIN (-3300 2500) SIG_NAME M_I_CPU0_SB_DQS_DN<0>
J 0
(-3290 2510);
DISPLAY 0.659574 (-3290 2510);
PAINT MONO (-3290 2510);
DISPLAY INVISIBLE (-3290 2510);
FORCEPROP 1 LASTPIN (-3300 2500) BN 0
J 0
(-3312 2508);
DISPLAY 0.489362 (-3312 2508);
PAINT GREEN (-3312 2508);
FORCEPROP 2 LAST CDS_LIB mstr_standard
J 0
(-3250 2500);
DISPLAY 0.723404 (-3250 2500);
PAINT MONO (-3250 2500);
DISPLAY INVISIBLE (-3250 2500);
FORCEPROP 1 LAST BODY_TYPE PLUMBING
J 0
(-3250 2550);
DISPLAY 0.872340 (-3250 2550);
PAINT GREEN (-3250 2550);
DISPLAY INVISIBLE (-3250 2550);
FORCEPROP 1 LAST HDL_TAP TRUE
J 0
(-2925 2375);
DISPLAY 0.872340 (-2925 2375);
DISPLAY INVISIBLE (-2925 2375);
FORCEPROP 1 LAST PATH I227
J 0
(-3252 2500);
DISPLAY 0.872340 (-3252 2500);
PAINT GREEN (-3252 2500);
DISPLAY INVISIBLE (-3252 2500);
FORCEADD TAP..1
(-3450 3150);
FORCEPROP 3 LASTPIN (-3500 3150) SIG_NAME M_I_CPU0_SB_DQS_DP<6>
J 0
(-3490 3160);
DISPLAY 0.659574 (-3490 3160);
PAINT MONO (-3490 3160);
DISPLAY INVISIBLE (-3490 3160);
FORCEPROP 1 LASTPIN (-3500 3150) BN 6
J 0
(-3512 3158);
DISPLAY 0.489362 (-3512 3158);
PAINT GREEN (-3512 3158);
FORCEPROP 2 LAST CDS_LIB mstr_standard
J 0
(-3450 3150);
DISPLAY 0.723404 (-3450 3150);
PAINT MONO (-3450 3150);
DISPLAY INVISIBLE (-3450 3150);
FORCEPROP 1 LAST BODY_TYPE PLUMBING
J 0
(-3450 3200);
DISPLAY 0.872340 (-3450 3200);
PAINT GREEN (-3450 3200);
DISPLAY INVISIBLE (-3450 3200);
FORCEPROP 1 LAST HDL_TAP TRUE
J 0
(-3125 3025);
DISPLAY 0.872340 (-3125 3025);
DISPLAY INVISIBLE (-3125 3025);
FORCEPROP 1 LAST PATH I228
J 0
(-3452 3150);
DISPLAY 0.872340 (-3452 3150);
PAINT GREEN (-3452 3150);
DISPLAY INVISIBLE (-3452 3150);
FORCEADD TAP..1
(-3450 3250);
FORCEPROP 3 LASTPIN (-3500 3250) SIG_NAME M_I_CPU0_SB_DQS_DP<7>
J 0
(-3490 3260);
DISPLAY 0.659574 (-3490 3260);
PAINT MONO (-3490 3260);
DISPLAY INVISIBLE (-3490 3260);
FORCEPROP 1 LASTPIN (-3500 3250) BN 7
J 0
(-3512 3258);
DISPLAY 0.489362 (-3512 3258);
PAINT GREEN (-3512 3258);
FORCEPROP 2 LAST CDS_LIB mstr_standard
J 0
(-3450 3250);
DISPLAY 0.723404 (-3450 3250);
PAINT MONO (-3450 3250);
DISPLAY INVISIBLE (-3450 3250);
FORCEPROP 1 LAST BODY_TYPE PLUMBING
J 0
(-3450 3300);
DISPLAY 0.872340 (-3450 3300);
PAINT GREEN (-3450 3300);
DISPLAY INVISIBLE (-3450 3300);
FORCEPROP 1 LAST HDL_TAP TRUE
J 0
(-3125 3125);
DISPLAY 0.872340 (-3125 3125);
DISPLAY INVISIBLE (-3125 3125);
FORCEPROP 1 LAST PATH I229
J 0
(-3452 3250);
DISPLAY 0.872340 (-3452 3250);
PAINT GREEN (-3452 3250);
DISPLAY INVISIBLE (-3452 3250);
FORCEADD TAP..1
R 2
(-7700 3350);
FORCEPROP 3 LASTPIN (-7650 3350) SIG_NAME M_I_CPU0_SB_CB<2>
J 0
(-7640 3360);
DISPLAY 0.659574 (-7640 3360);
PAINT MONO (-7640 3360);
DISPLAY INVISIBLE (-7640 3360);
FORCEPROP 1 LASTPIN (-7650 3350) BN 2
J 2
(-7638 3358);
DISPLAY 0.489362 (-7638 3358);
PAINT GREEN (-7638 3358);
FORCEPROP 2 LAST CDS_LIB mstr_standard
J 0
(-7700 3350);
DISPLAY 0.723404 (-7700 3350);
PAINT MONO (-7700 3350);
DISPLAY INVISIBLE (-7700 3350);
FORCEPROP 1 LAST BODY_TYPE PLUMBING
J 2
(-7700 3400);
DISPLAY 0.872340 (-7700 3400);
PAINT GREEN (-7700 3400);
DISPLAY INVISIBLE (-7700 3400);
FORCEPROP 1 LAST HDL_TAP TRUE
J 2
(-8025 3225);
DISPLAY 0.872340 (-8025 3225);
DISPLAY INVISIBLE (-8025 3225);
FORCEPROP 1 LAST PATH I23
J 2
(-7698 3350);
DISPLAY 0.872340 (-7698 3350);
PAINT GREEN (-7698 3350);
DISPLAY INVISIBLE (-7698 3350);
FORCEADD TAP..1
(-3450 3050);
FORCEPROP 3 LASTPIN (-3500 3050) SIG_NAME M_I_CPU0_SB_DQS_DP<5>
J 0
(-3490 3060);
DISPLAY 0.659574 (-3490 3060);
PAINT MONO (-3490 3060);
DISPLAY INVISIBLE (-3490 3060);
FORCEPROP 1 LASTPIN (-3500 3050) BN 5
J 0
(-3512 3058);
DISPLAY 0.489362 (-3512 3058);
PAINT GREEN (-3512 3058);
FORCEPROP 2 LAST CDS_LIB mstr_standard
J 0
(-3450 3050);
DISPLAY 0.723404 (-3450 3050);
PAINT MONO (-3450 3050);
DISPLAY INVISIBLE (-3450 3050);
FORCEPROP 1 LAST BODY_TYPE PLUMBING
J 0
(-3450 3100);
DISPLAY 0.872340 (-3450 3100);
PAINT GREEN (-3450 3100);
DISPLAY INVISIBLE (-3450 3100);
FORCEPROP 1 LAST HDL_TAP TRUE
J 0
(-3125 2925);
DISPLAY 0.872340 (-3125 2925);
DISPLAY INVISIBLE (-3125 2925);
FORCEPROP 1 LAST PATH I230
J 0
(-3452 3050);
DISPLAY 0.872340 (-3452 3050);
PAINT GREEN (-3452 3050);
DISPLAY INVISIBLE (-3452 3050);
FORCEADD TAP..1
(-3450 2950);
FORCEPROP 3 LASTPIN (-3500 2950) SIG_NAME M_I_CPU0_SB_DQS_DP<4>
J 0
(-3490 2960);
DISPLAY 0.659574 (-3490 2960);
PAINT MONO (-3490 2960);
DISPLAY INVISIBLE (-3490 2960);
FORCEPROP 1 LASTPIN (-3500 2950) BN 4
J 0
(-3512 2958);
DISPLAY 0.489362 (-3512 2958);
PAINT GREEN (-3512 2958);
FORCEPROP 2 LAST CDS_LIB mstr_standard
J 0
(-3450 2950);
DISPLAY 0.723404 (-3450 2950);
PAINT MONO (-3450 2950);
DISPLAY INVISIBLE (-3450 2950);
FORCEPROP 1 LAST BODY_TYPE PLUMBING
J 0
(-3450 3000);
DISPLAY 0.872340 (-3450 3000);
PAINT GREEN (-3450 3000);
DISPLAY INVISIBLE (-3450 3000);
FORCEPROP 1 LAST HDL_TAP TRUE
J 0
(-3125 2825);
DISPLAY 0.872340 (-3125 2825);
DISPLAY INVISIBLE (-3125 2825);
FORCEPROP 1 LAST PATH I231
J 0
(-3452 2950);
DISPLAY 0.872340 (-3452 2950);
PAINT GREEN (-3452 2950);
DISPLAY INVISIBLE (-3452 2950);
FORCEADD TAP..1
(-3450 2850);
FORCEPROP 3 LASTPIN (-3500 2850) SIG_NAME M_I_CPU0_SB_DQS_DP<3>
J 0
(-3490 2860);
DISPLAY 0.659574 (-3490 2860);
PAINT MONO (-3490 2860);
DISPLAY INVISIBLE (-3490 2860);
FORCEPROP 1 LASTPIN (-3500 2850) BN 3
J 0
(-3512 2858);
DISPLAY 0.489362 (-3512 2858);
PAINT GREEN (-3512 2858);
FORCEPROP 2 LAST CDS_LIB mstr_standard
J 0
(-3450 2850);
DISPLAY 0.723404 (-3450 2850);
PAINT MONO (-3450 2850);
DISPLAY INVISIBLE (-3450 2850);
FORCEPROP 1 LAST BODY_TYPE PLUMBING
J 0
(-3450 2900);
DISPLAY 0.872340 (-3450 2900);
PAINT GREEN (-3450 2900);
DISPLAY INVISIBLE (-3450 2900);
FORCEPROP 1 LAST HDL_TAP TRUE
J 0
(-3125 2725);
DISPLAY 0.872340 (-3125 2725);
DISPLAY INVISIBLE (-3125 2725);
FORCEPROP 1 LAST PATH I232
J 0
(-3452 2850);
DISPLAY 0.872340 (-3452 2850);
PAINT GREEN (-3452 2850);
DISPLAY INVISIBLE (-3452 2850);
FORCEADD TAP..1
(-3450 2650);
FORCEPROP 3 LASTPIN (-3500 2650) SIG_NAME M_I_CPU0_SB_DQS_DP<1>
J 0
(-3490 2660);
DISPLAY 0.659574 (-3490 2660);
PAINT MONO (-3490 2660);
DISPLAY INVISIBLE (-3490 2660);
FORCEPROP 1 LASTPIN (-3500 2650) BN 1
J 0
(-3512 2658);
DISPLAY 0.489362 (-3512 2658);
PAINT GREEN (-3512 2658);
FORCEPROP 2 LAST CDS_LIB mstr_standard
J 0
(-3450 2650);
DISPLAY 0.723404 (-3450 2650);
PAINT MONO (-3450 2650);
DISPLAY INVISIBLE (-3450 2650);
FORCEPROP 1 LAST BODY_TYPE PLUMBING
J 0
(-3450 2700);
DISPLAY 0.872340 (-3450 2700);
PAINT GREEN (-3450 2700);
DISPLAY INVISIBLE (-3450 2700);
FORCEPROP 1 LAST HDL_TAP TRUE
J 0
(-3125 2525);
DISPLAY 0.872340 (-3125 2525);
DISPLAY INVISIBLE (-3125 2525);
FORCEPROP 1 LAST PATH I233
J 0
(-3452 2650);
DISPLAY 0.872340 (-3452 2650);
PAINT GREEN (-3452 2650);
DISPLAY INVISIBLE (-3452 2650);
FORCEADD TAP..1
(-3450 2750);
FORCEPROP 3 LASTPIN (-3500 2750) SIG_NAME M_I_CPU0_SB_DQS_DP<2>
J 0
(-3490 2760);
DISPLAY 0.659574 (-3490 2760);
PAINT MONO (-3490 2760);
DISPLAY INVISIBLE (-3490 2760);
FORCEPROP 1 LASTPIN (-3500 2750) BN 2
J 0
(-3512 2758);
DISPLAY 0.489362 (-3512 2758);
PAINT GREEN (-3512 2758);
FORCEPROP 2 LAST CDS_LIB mstr_standard
J 0
(-3450 2750);
DISPLAY 0.723404 (-3450 2750);
PAINT MONO (-3450 2750);
DISPLAY INVISIBLE (-3450 2750);
FORCEPROP 1 LAST BODY_TYPE PLUMBING
J 0
(-3450 2800);
DISPLAY 0.872340 (-3450 2800);
PAINT GREEN (-3450 2800);
DISPLAY INVISIBLE (-3450 2800);
FORCEPROP 1 LAST HDL_TAP TRUE
J 0
(-3125 2625);
DISPLAY 0.872340 (-3125 2625);
DISPLAY INVISIBLE (-3125 2625);
FORCEPROP 1 LAST PATH I234
J 0
(-3452 2750);
DISPLAY 0.872340 (-3452 2750);
PAINT GREEN (-3452 2750);
DISPLAY INVISIBLE (-3452 2750);
FORCEADD TAP..1
(-3450 2550);
FORCEPROP 3 LASTPIN (-3500 2550) SIG_NAME M_I_CPU0_SB_DQS_DP<0>
J 0
(-3490 2560);
DISPLAY 0.659574 (-3490 2560);
PAINT MONO (-3490 2560);
DISPLAY INVISIBLE (-3490 2560);
FORCEPROP 1 LASTPIN (-3500 2550) BN 0
J 0
(-3512 2558);
DISPLAY 0.489362 (-3512 2558);
PAINT GREEN (-3512 2558);
FORCEPROP 2 LAST CDS_LIB mstr_standard
J 0
(-3450 2550);
DISPLAY 0.723404 (-3450 2550);
PAINT MONO (-3450 2550);
DISPLAY INVISIBLE (-3450 2550);
FORCEPROP 1 LAST BODY_TYPE PLUMBING
J 0
(-3450 2600);
DISPLAY 0.872340 (-3450 2600);
PAINT GREEN (-3450 2600);
DISPLAY INVISIBLE (-3450 2600);
FORCEPROP 1 LAST HDL_TAP TRUE
J 0
(-3125 2425);
DISPLAY 0.872340 (-3125 2425);
DISPLAY INVISIBLE (-3125 2425);
FORCEPROP 1 LAST PATH I235
J 0
(-3452 2550);
DISPLAY 0.872340 (-3452 2550);
PAINT GREEN (-3452 2550);
DISPLAY INVISIBLE (-3452 2550);
FORCEADD SCONN288_DDR506112002KQ..2
(-4400 3500);
FORCEPROP 1 LAST LOCATION J18
J 0
(-5000 4825);
DISPLAY 0.468085 (-5000 4825);
PAINT SKYBLUE (-5000 4825);
FORCEPROP 0 LAST $SEC 2
J 0
(-4850 4975);
DISPLAY 0.680851 (-4850 4975);
PAINT MONO (-4850 4975);
DISPLAY INVISIBLE (-4850 4975);
FORCEPROP 0 LAST CDS_SEC 2
J 0
(-4850 4975);
DISPLAY 1.021277 (-4850 4975);
DISPLAY INVISIBLE (-4850 4975);
FORCEPROP 0 LASTPIN (-3650 3550) $PN 12
J 0
(-3640 3560);
DISPLAY 0.680851 (-3640 3560);
PAINT MONO (-3640 3560);
FORCEPROP 0 LASTPIN (-3650 3600) $PN 11
J 0
(-3640 3610);
DISPLAY 0.680851 (-3640 3610);
PAINT MONO (-3640 3610);
FORCEPROP 0 LASTPIN (-3650 2500) $PN 105
J 0
(-3640 2510);
DISPLAY 0.680851 (-3640 2510);
PAINT MONO (-3640 2510);
FORCEPROP 0 LASTPIN (-3650 2550) $PN 104
J 0
(-3640 2560);
DISPLAY 0.680851 (-3640 2560);
PAINT MONO (-3640 2560);
FORCEPROP 0 LASTPIN (-3650 3650) $PN 23
J 0
(-3640 3660);
DISPLAY 0.680851 (-3640 3660);
PAINT MONO (-3640 3660);
FORCEPROP 0 LASTPIN (-3650 3700) $PN 22
J 0
(-3640 3710);
DISPLAY 0.680851 (-3640 3710);
PAINT MONO (-3640 3710);
FORCEPROP 0 LASTPIN (-3650 2600) $PN 116
J 0
(-3640 2610);
DISPLAY 0.680851 (-3640 2610);
PAINT MONO (-3640 2610);
FORCEPROP 0 LASTPIN (-3650 2650) $PN 115
J 0
(-3640 2660);
DISPLAY 0.680851 (-3640 2660);
PAINT MONO (-3640 2660);
FORCEPROP 0 LASTPIN (-3650 3750) $PN 34
J 0
(-3640 3760);
DISPLAY 0.680851 (-3640 3760);
PAINT MONO (-3640 3760);
FORCEPROP 0 LASTPIN (-3650 3800) $PN 33
J 0
(-3640 3810);
DISPLAY 0.680851 (-3640 3810);
PAINT MONO (-3640 3810);
FORCEPROP 0 LASTPIN (-3650 2700) $PN 127
J 0
(-3640 2710);
DISPLAY 0.680851 (-3640 2710);
PAINT MONO (-3640 2710);
FORCEPROP 0 LASTPIN (-3650 2750) $PN 126
J 0
(-3640 2760);
DISPLAY 0.680851 (-3640 2760);
PAINT MONO (-3640 2760);
FORCEPROP 0 LASTPIN (-3650 3850) $PN 45
J 0
(-3640 3860);
DISPLAY 0.680851 (-3640 3860);
PAINT MONO (-3640 3860);
FORCEPROP 0 LASTPIN (-3650 3900) $PN 44
J 0
(-3640 3910);
DISPLAY 0.680851 (-3640 3910);
PAINT MONO (-3640 3910);
FORCEPROP 0 LASTPIN (-3650 2800) $PN 138
J 0
(-3640 2810);
DISPLAY 0.680851 (-3640 2810);
PAINT MONO (-3640 2810);
FORCEPROP 0 LASTPIN (-3650 2850) $PN 137
J 0
(-3640 2860);
DISPLAY 0.680851 (-3640 2860);
PAINT MONO (-3640 2860);
FORCEPROP 0 LASTPIN (-3650 3950) $PN 56
J 0
(-3640 3960);
DISPLAY 0.680851 (-3640 3960);
PAINT MONO (-3640 3960);
FORCEPROP 0 LASTPIN (-3650 4000) $PN 55
J 0
(-3640 4010);
DISPLAY 0.680851 (-3640 4010);
PAINT MONO (-3640 4010);
FORCEPROP 0 LASTPIN (-3650 2900) $PN 238
J 0
(-3640 2910);
DISPLAY 0.680851 (-3640 2910);
PAINT MONO (-3640 2910);
FORCEPROP 0 LASTPIN (-3650 2950) $PN 239
J 0
(-3640 2960);
DISPLAY 0.680851 (-3640 2960);
PAINT MONO (-3640 2960);
FORCEPROP 0 LASTPIN (-3650 4050) $PN 156
J 0
(-3640 4060);
DISPLAY 0.680851 (-3640 4060);
PAINT MONO (-3640 4060);
FORCEPROP 0 LASTPIN (-3650 4100) $PN 157
J 0
(-3640 4110);
DISPLAY 0.680851 (-3640 4110);
PAINT MONO (-3640 4110);
FORCEPROP 0 LASTPIN (-3650 3000) $PN 249
J 0
(-3640 3010);
DISPLAY 0.680851 (-3640 3010);
PAINT MONO (-3640 3010);
FORCEPROP 0 LASTPIN (-3650 3050) $PN 250
J 0
(-3640 3060);
DISPLAY 0.680851 (-3640 3060);
PAINT MONO (-3640 3060);
FORCEPROP 0 LASTPIN (-3650 4150) $PN 167
J 0
(-3640 4160);
DISPLAY 0.680851 (-3640 4160);
PAINT MONO (-3640 4160);
FORCEPROP 0 LASTPIN (-3650 4200) $PN 168
J 0
(-3640 4210);
DISPLAY 0.680851 (-3640 4210);
PAINT MONO (-3640 4210);
FORCEPROP 0 LASTPIN (-3650 3100) $PN 260
J 0
(-3640 3110);
DISPLAY 0.680851 (-3640 3110);
PAINT MONO (-3640 3110);
FORCEPROP 0 LASTPIN (-3650 3150) $PN 261
J 0
(-3640 3160);
DISPLAY 0.680851 (-3640 3160);
PAINT MONO (-3640 3160);
FORCEPROP 0 LASTPIN (-3650 4250) $PN 178
J 0
(-3640 4260);
DISPLAY 0.680851 (-3640 4260);
PAINT MONO (-3640 4260);
FORCEPROP 0 LASTPIN (-3650 4300) $PN 179
J 0
(-3640 4310);
DISPLAY 0.680851 (-3640 4310);
PAINT MONO (-3640 4310);
FORCEPROP 0 LASTPIN (-3650 3200) $PN 271
J 0
(-3640 3210);
DISPLAY 0.680851 (-3640 3210);
PAINT MONO (-3640 3210);
FORCEPROP 0 LASTPIN (-3650 3250) $PN 272
J 0
(-3640 3260);
DISPLAY 0.680851 (-3640 3260);
PAINT MONO (-3640 3260);
FORCEPROP 0 LASTPIN (-3650 4350) $PN 189
J 0
(-3640 4360);
DISPLAY 0.680851 (-3640 4360);
PAINT MONO (-3640 4360);
FORCEPROP 0 LASTPIN (-3650 4400) $PN 190
J 0
(-3640 4410);
DISPLAY 0.680851 (-3640 4410);
PAINT MONO (-3640 4410);
FORCEPROP 0 LASTPIN (-3650 3300) $PN 282
J 0
(-3640 3310);
DISPLAY 0.680851 (-3640 3310);
PAINT MONO (-3640 3310);
FORCEPROP 0 LASTPIN (-3650 3350) $PN 283
J 0
(-3640 3360);
DISPLAY 0.680851 (-3640 3360);
PAINT MONO (-3640 3360);
FORCEPROP 0 LASTPIN (-3650 4450) $PN 200
J 0
(-3640 4460);
DISPLAY 0.680851 (-3640 4460);
PAINT MONO (-3640 4460);
FORCEPROP 0 LASTPIN (-3650 4500) $PN 201
J 0
(-3640 4510);
DISPLAY 0.680851 (-3640 4510);
PAINT MONO (-3640 4510);
FORCEPROP 0 LASTPIN (-3650 3400) $PN 94
J 0
(-3640 3410);
DISPLAY 0.680851 (-3640 3410);
PAINT MONO (-3640 3410);
FORCEPROP 0 LASTPIN (-3650 3450) $PN 93
J 0
(-3640 3460);
DISPLAY 0.680851 (-3640 3460);
PAINT MONO (-3640 3460);
FORCEPROP 2 LAST VALUE SCONN288_DDR506112002KQ
J 0
(-4850 4875);
DISPLAY 0.489362 (-4850 4875);
PAINT SKYBLUE (-4850 4875);
FORCEPROP 1 LAST MATERIAL IO
J 0
(-5000 4675);
DISPLAY 0.468085 (-5000 4675);
PAINT SKYBLUE (-5000 4675);
FORCEPROP 2 LAST PART_TYPE SMLF
J 0
(-4850 4925);
DISPLAY 1.021277 (-4850 4925);
FORCEPROP 2 LAST CDS_LIB pure_quanta
J 0
(-4400 3500);
DISPLAY INVISIBLE (-4400 3500);
FORCEPROP 1 LAST NEEDS_NO_SIZE TRUE
J 0
(-4400 3500);
DISPLAY 0.723404 (-4400 3500);
PAINT GREEN (-4400 3500);
DISPLAY INVISIBLE (-4400 3500);
FORCEPROP 1 LAST CDS_LMAN_SYM_OUTLINE -600,1150,600,-1150
J 0
(-4400 3500);
DISPLAY 0.468085 (-4400 3500);
PAINT GREEN (-4400 3500);
DISPLAY INVISIBLE (-4400 3500);
FORCEPROP 1 LAST PATH I236
J 0
(-4400 3500);
DISPLAY 0.723404 (-4400 3500);
PAINT GREEN (-4400 3500);
DISPLAY INVISIBLE (-4400 3500);
FORCEPROP 1 LAST PART_NUMBER DFHST8FS479
J 0
(-5000 4750);
DISPLAY 0.468085 (-5000 4750);
PAINT SKYBLUE (-5000 4750);
DISPLAY INVISIBLE (-5000 4750);
FORCEADD GND..1
(-2825 5550);
FORCEPROP 3 LASTPIN (-2825 5600) SIG_NAME GND\g
J 0
(-2815 5610);
DISPLAY 0.659574 (-2815 5610);
PAINT MONO (-2815 5610);
DISPLAY INVISIBLE (-2815 5610);
FORCEPROP 2 LAST ROOM MEM_EFGH_DECOUPLING_CAPS
J 0
(-2800 5625);
DISPLAY 0.659574 (-2800 5625);
PAINT RED (-2800 5625);
DISPLAY INVISIBLE (-2800 5625);
FORCEPROP 1 LAST SIZE 1B
J 0
(-2750 5500);
DISPLAY 0.723404 (-2750 5500);
PAINT GREEN (-2750 5500);
DISPLAY INVISIBLE (-2750 5500);
FORCEPROP 2 LAST BOM_COST MEM
J 0
(-2800 5675);
DISPLAY 0.659574 (-2800 5675);
DISPLAY INVISIBLE (-2800 5675);
FORCEPROP 2 LAST CDS_LIB pure_quanta_power
J 0
(-2825 5550);
DISPLAY INVISIBLE (-2825 5550);
FORCEPROP 1 LAST HDL_POWER GND
J 0
(-2825 5700);
DISPLAY 0.723404 (-2825 5700);
PAINT GREEN (-2825 5700);
DISPLAY INVISIBLE (-2825 5700);
FORCEPROP 1 LAST PATH I237
J 0
(-2750 5550);
DISPLAY 0.872340 (-2750 5550);
PAINT AQUA (-2750 5550);
DISPLAY INVISIBLE (-2750 5550);
FORCEADD Q_CAP..1
R 2
(-2825 5900);
FORCEPROP 1 LAST LOCATION C162
J 2
(-2875 6000);
DISPLAY 0.489362 (-2875 6000);
PAINT SKYBLUE (-2875 6000);
FORCEPROP 0 LAST $SEC 1
J 0
(-2875 6050);
DISPLAY 0.680851 (-2875 6050);
PAINT MONO (-2875 6050);
DISPLAY INVISIBLE (-2875 6050);
FORCEPROP 0 LAST CDS_SEC 1
J 0
(-2875 6050);
DISPLAY 0.680851 (-2875 6050);
DISPLAY INVISIBLE (-2875 6050);
FORCEPROP 1 LASTPIN (-2825 6000) $PN 1
J 2
(-2835 5980);
DISPLAY 0.489362 (-2835 5980);
PAINT MONO (-2835 5980);
FORCEPROP 1 LASTPIN (-2825 5800) $PN 2
J 2
(-2835 5780);
DISPLAY 0.489362 (-2835 5780);
PAINT MONO (-2835 5780);
FORCEPROP 1 LAST MATERIAL X6S
J 2
(-2875 5800);
DISPLAY 0.489362 (-2875 5800);
PAINT SKYBLUE (-2875 5800);
FORCEPROP 1 LAST TOLERANCE 10%
J 2
(-2875 5850);
DISPLAY 0.489362 (-2875 5850);
PAINT SKYBLUE (-2875 5850);
FORCEPROP 1 LAST VALUE 10UF
J 2
(-2875 5950);
DISPLAY 0.489362 (-2875 5950);
PAINT SKYBLUE (-2875 5950);
FORCEPROP 1 LAST VOLTAGE 25V
J 2
(-2875 5900);
DISPLAY 0.489362 (-2875 5900);
PAINT SKYBLUE (-2875 5900);
FORCEPROP 1 LAST PACK_TYPE C0805
J 2
(-2875 5700);
DISPLAY 0.489362 (-2875 5700);
PAINT SKYBLUE (-2875 5700);
FORCEPROP 0 LAST BOM_COST MEM
J 2
(-2880 6045);
DISPLAY 0.595745 (-2880 6045);
PAINT MONO (-2880 6045);
DISPLAY INVISIBLE (-2880 6045);
FORCEPROP 2 LAST CDS_LIB pure_quanta
J 0
(-2825 5900);
DISPLAY INVISIBLE (-2825 5900);
FORCEPROP 2 LAST ROOM 
J 2
(-2880 6045);
DISPLAY 0.595745 (-2880 6045);
PAINT RED (-2880 6045);
DISPLAY INVISIBLE (-2880 6045);
FORCEPROP 1 LAST PATH I238
J 2
(-2875 6050);
DISPLAY 0.978723 (-2875 6050);
PAINT WHITE (-2875 6050);
DISPLAY INVISIBLE (-2875 6050);
FORCEPROP 1 LAST PART_NUMBER CH6104KEA00
J 2
(-2875 5750);
DISPLAY 0.489362 (-2875 5750);
PAINT SKYBLUE (-2875 5750);
DISPLAY INVISIBLE (-2875 5750);
FORCEADD Q_CAP..1
R 2
(-2250 5900);
FORCEPROP 1 LAST LOCATION C163
J 2
(-2300 6000);
DISPLAY 0.489362 (-2300 6000);
PAINT SKYBLUE (-2300 6000);
FORCEPROP 0 LAST $SEC 1
J 0
(-2300 6050);
DISPLAY 0.680851 (-2300 6050);
PAINT MONO (-2300 6050);
DISPLAY INVISIBLE (-2300 6050);
FORCEPROP 0 LAST CDS_SEC 1
J 0
(-2300 6050);
DISPLAY 0.680851 (-2300 6050);
DISPLAY INVISIBLE (-2300 6050);
FORCEPROP 1 LASTPIN (-2250 6000) $PN 1
J 2
(-2260 5980);
DISPLAY 0.489362 (-2260 5980);
PAINT MONO (-2260 5980);
FORCEPROP 1 LASTPIN (-2250 5800) $PN 2
J 2
(-2260 5780);
DISPLAY 0.489362 (-2260 5780);
PAINT MONO (-2260 5780);
FORCEPROP 1 LAST MATERIAL X6S
J 2
(-2300 5800);
DISPLAY 0.489362 (-2300 5800);
PAINT SKYBLUE (-2300 5800);
FORCEPROP 1 LAST TOLERANCE 10%
J 2
(-2300 5850);
DISPLAY 0.489362 (-2300 5850);
PAINT SKYBLUE (-2300 5850);
FORCEPROP 1 LAST VALUE 10UF
J 2
(-2300 5950);
DISPLAY 0.489362 (-2300 5950);
PAINT SKYBLUE (-2300 5950);
FORCEPROP 1 LAST VOLTAGE 25V
J 2
(-2300 5900);
DISPLAY 0.489362 (-2300 5900);
PAINT SKYBLUE (-2300 5900);
FORCEPROP 1 LAST PACK_TYPE C0805
J 2
(-2300 5700);
DISPLAY 0.489362 (-2300 5700);
PAINT SKYBLUE (-2300 5700);
FORCEPROP 0 LAST BOM_COST MEM
J 2
(-2305 6045);
DISPLAY 0.595745 (-2305 6045);
PAINT MONO (-2305 6045);
DISPLAY INVISIBLE (-2305 6045);
FORCEPROP 2 LAST CDS_LIB pure_quanta
J 0
(-2250 5900);
DISPLAY INVISIBLE (-2250 5900);
FORCEPROP 2 LAST ROOM 
J 2
(-2305 6045);
DISPLAY 0.595745 (-2305 6045);
PAINT RED (-2305 6045);
DISPLAY INVISIBLE (-2305 6045);
FORCEPROP 1 LAST PATH I239
J 2
(-2300 6050);
DISPLAY 0.978723 (-2300 6050);
PAINT WHITE (-2300 6050);
DISPLAY INVISIBLE (-2300 6050);
FORCEPROP 1 LAST PART_NUMBER CH6104KEA00
J 2
(-2300 5750);
DISPLAY 0.489362 (-2300 5750);
PAINT SKYBLUE (-2300 5750);
DISPLAY INVISIBLE (-2300 5750);
FORCEADD TAP..1
R 2
(-7700 3400);
FORCEPROP 3 LASTPIN (-7650 3400) SIG_NAME M_I_CPU0_SB_CB<3>
J 0
(-7640 3410);
DISPLAY 0.659574 (-7640 3410);
PAINT MONO (-7640 3410);
DISPLAY INVISIBLE (-7640 3410);
FORCEPROP 1 LASTPIN (-7650 3400) BN 3
J 2
(-7638 3408);
DISPLAY 0.489362 (-7638 3408);
PAINT GREEN (-7638 3408);
FORCEPROP 2 LAST CDS_LIB mstr_standard
J 0
(-7700 3400);
DISPLAY 0.723404 (-7700 3400);
PAINT MONO (-7700 3400);
DISPLAY INVISIBLE (-7700 3400);
FORCEPROP 1 LAST BODY_TYPE PLUMBING
J 2
(-7700 3450);
DISPLAY 0.872340 (-7700 3450);
PAINT GREEN (-7700 3450);
DISPLAY INVISIBLE (-7700 3450);
FORCEPROP 1 LAST HDL_TAP TRUE
J 2
(-8025 3275);
DISPLAY 0.872340 (-8025 3275);
DISPLAY INVISIBLE (-8025 3275);
FORCEPROP 1 LAST PATH I24
J 2
(-7698 3400);
DISPLAY 0.872340 (-7698 3400);
PAINT GREEN (-7698 3400);
DISPLAY INVISIBLE (-7698 3400);
FORCEADD UNIVERSAL_POWER..1
(-2825 6225);
FORCEPROP 3 LASTPIN (-2825 6175) SIG_NAME P12V_MEM_CPU0\g
J 0
(-2815 6185);
DISPLAY 0.659574 (-2815 6185);
PAINT MONO (-2815 6185);
DISPLAY INVISIBLE (-2815 6185);
FORCEPROP 1 LAST HDL_POWER P12V_MEM_CPU0
J 1
(-2850 6275);
DISPLAY 0.489362 (-2850 6275);
PAINT GREEN (-2850 6275);
FORCEPROP 2 LAST CDS_LIB pure_quanta_power
J 0
(-2825 6225);
DISPLAY INVISIBLE (-2825 6225);
FORCEPROP 2 LAST BOM_COST VR_SYSTEM
J 0
(-2825 6325);
DISPLAY 0.617021 (-2825 6325);
PAINT PURPLE (-2825 6325);
DISPLAY INVISIBLE (-2825 6325);
FORCEPROP 1 LAST PATH I240
J 0
(-2775 6250);
DISPLAY 0.872340 (-2775 6250);
PAINT AQUA (-2775 6250);
DISPLAY INVISIBLE (-2775 6250);
FORCEADD OFFPAGE..1
(-8400 2675);
FORCEPROP 2 LAST $XR5 97 
J 0
(-9102 2675);
DISPLAY 0.638298 (-9102 2675);
PAINT MONO (-9102 2675);
FORCEPROP 2 LAST $XR4 96 
J 0
(-9012 2675);
DISPLAY 0.638298 (-9012 2675);
PAINT MONO (-9012 2675);
FORCEPROP 2 LAST $XR3 95 
J 0
(-8922 2675);
DISPLAY 0.638298 (-8922 2675);
PAINT MONO (-8922 2675);
FORCEPROP 2 LAST $XR2 93 
J 0
(-8832 2675);
DISPLAY 0.638298 (-8832 2675);
PAINT MONO (-8832 2675);
FORCEPROP 2 LAST $XR1 92 
J 0
(-8742 2675);
DISPLAY 0.638298 (-8742 2675);
PAINT MONO (-8742 2675);
FORCEPROP 2 LAST $XR0 159 
J 0
(-8652 2675);
DISPLAY 0.638298 (-8652 2675);
PAINT MONO (-8652 2675);
FORCEPROP 2 LAST CDS_LIB mstr_standard
J 0
(-8400 2675);
DISPLAY 0.808511 (-8400 2675);
DISPLAY INVISIBLE (-8400 2675);
FORCEPROP 1 LAST OFFPAGE TRUE
J 0
(-8075 2550);
DISPLAY 0.872340 (-8075 2550);
PAINT GREEN (-8075 2550);
DISPLAY INVISIBLE (-8075 2550);
FORCEPROP 1 LAST COMMENT_BODY TRUE
J 0
(-8275 2575);
DISPLAY 0.872340 (-8275 2575);
PAINT GREEN (-8275 2575);
DISPLAY INVISIBLE (-8275 2575);
FORCEPROP 2 LAST PATH I241
J 0
(-8675 2725);
DISPLAY 0.680851 (-8675 2725);
DISPLAY INVISIBLE (-8675 2725);
FORCEADD Q_RES..1
(-7750 2675);
FORCEPROP 1 LAST LOCATION R1576
J 0
(-7800 2700);
DISPLAY 0.510638 (-7800 2700);
PAINT SKYBLUE (-7800 2700);
FORCEPROP 0 LAST $SEC 1
J 0
(-7800 2775);
DISPLAY 0.680851 (-7800 2775);
PAINT MONO (-7800 2775);
DISPLAY INVISIBLE (-7800 2775);
FORCEPROP 0 LAST CDS_SEC 1
J 0
(-7800 2775);
DISPLAY 0.680851 (-7800 2775);
DISPLAY INVISIBLE (-7800 2775);
FORCEPROP 1 LASTPIN (-7850 2675) $PN 1
J 0
(-7838 2687);
DISPLAY 0.787234 (-7838 2687);
PAINT MONO (-7838 2687);
FORCEPROP 1 LASTPIN (-7650 2675) $PN 2
J 0
(-7688 2687);
DISPLAY 0.787234 (-7688 2687);
PAINT MONO (-7688 2687);
FORCEPROP 1 LAST VALUE 49.9
J 2
(-7600 2725);
DISPLAY 0.510638 (-7600 2725);
PAINT SKYBLUE (-7600 2725);
FORCEPROP 1 LAST TOLERANCE 1%
J 0
(-7750 2575);
DISPLAY 0.978723 (-7750 2575);
DISPLAY INVISIBLE (-7750 2575);
FORCEPROP 1 LAST WATTAGE 1/16W
J 2
(-7775 2525);
DISPLAY 0.978723 (-7775 2525);
DISPLAY INVISIBLE (-7775 2525);
FORCEPROP 1 LAST PACK_TYPE 0402LF
J 0
(-7500 2525);
DISPLAY 0.978723 (-7500 2525);
DISPLAY INVISIBLE (-7500 2525);
FORCEPROP 1 LAST MATERIAL CHIP
J 0
(-7750 2525);
DISPLAY 0.978723 (-7750 2525);
DISPLAY INVISIBLE (-7750 2525);
FORCEPROP 2 LAST CDS_LIB pure_quanta
J 0
(-7750 2675);
DISPLAY INVISIBLE (-7750 2675);
FORCEPROP 1 LAST PATH I242
J 0
(-7800 2825);
DISPLAY 0.978723 (-7800 2825);
PAINT WHITE (-7800 2825);
DISPLAY INVISIBLE (-7800 2825);
FORCEPROP 1 LAST PART_NUMBER CS04992FB07
J 0
(-7800 2775);
DISPLAY 0.978723 (-7800 2775);
DISPLAY INVISIBLE (-7800 2775);
FORCEADD Q_RES..1
(-8150 2900);
FORCEPROP 1 LAST LOCATION R1683
J 0
(-8300 2900);
DISPLAY 0.510638 (-8300 2900);
FORCEPROP 0 LAST $SEC 1
J 0
(-8300 2950);
DISPLAY 0.680851 (-8300 2950);
PAINT MONO (-8300 2950);
DISPLAY INVISIBLE (-8300 2950);
FORCEPROP 0 LAST CDS_SEC 1
J 0
(-8300 2950);
DISPLAY 0.680851 (-8300 2950);
DISPLAY INVISIBLE (-8300 2950);
FORCEPROP 1 LASTPIN (-8250 2900) $PN 1
J 0
(-8238 2912);
DISPLAY 0.787234 (-8238 2912);
PAINT MONO (-8238 2912);
FORCEPROP 1 LASTPIN (-8050 2900) $PN 2
J 0
(-8088 2912);
DISPLAY 0.787234 (-8088 2912);
PAINT MONO (-8088 2912);
FORCEPROP 1 LAST MATERIAL CHIP
J 0
(-8250 2875);
DISPLAY 0.404255 (-8250 2875);
FORCEPROP 1 LAST PACK_TYPE 0402LF
J 0
(-8100 2875);
DISPLAY 0.404255 (-8100 2875);
FORCEPROP 1 LAST VALUE 10
J 2
(-8000 2900);
DISPLAY 0.404255 (-8000 2900);
FORCEPROP 1 LAST WATTAGE 1/16W
J 2
(-8175 2750);
DISPLAY 0.978723 (-8175 2750);
DISPLAY INVISIBLE (-8175 2750);
FORCEPROP 1 LAST TOLERANCE 1%
J 0
(-8150 2800);
DISPLAY 0.978723 (-8150 2800);
DISPLAY INVISIBLE (-8150 2800);
FORCEPROP 2 LAST CDS_LIB pure_quanta
J 0
(-8150 2900);
DISPLAY INVISIBLE (-8150 2900);
FORCEPROP 1 LAST PATH I243
J 0
(-8200 3050);
DISPLAY 0.978723 (-8200 3050);
PAINT WHITE (-8200 3050);
DISPLAY INVISIBLE (-8200 3050);
FORCEPROP 1 LAST PART_NUMBER CS01002FB07
J 0
(-8200 3000);
DISPLAY 0.978723 (-8200 3000);
DISPLAY INVISIBLE (-8200 3000);
FORCEADD OFFPAGE..6
(-8825 2800);
FORCEPROP 2 LAST $XR5 159 
J 0
(-9314 2764);
DISPLAY 0.638298 (-9314 2764);
PAINT MONO (-9314 2764);
FORCEPROP 2 LAST $XR4 97 
J 0
(-9194 2764);
DISPLAY 0.638298 (-9194 2764);
PAINT MONO (-9194 2764);
FORCEPROP 2 LAST $XR3 96 
J 0
(-9104 2764);
DISPLAY 0.638298 (-9104 2764);
PAINT MONO (-9104 2764);
FORCEPROP 2 LAST $XR2 95 
J 0
(-9284 2800);
DISPLAY 0.638298 (-9284 2800);
PAINT MONO (-9284 2800);
FORCEPROP 2 LAST $XR1 93 
J 0
(-9194 2800);
DISPLAY 0.638298 (-9194 2800);
PAINT MONO (-9194 2800);
FORCEPROP 2 LAST $XR0 92 
J 0
(-9104 2800);
DISPLAY 0.638298 (-9104 2800);
PAINT MONO (-9104 2800);
FORCEPROP 2 LAST CDS_LIB mstr_standard
J 0
(-8825 2800);
DISPLAY 0.808511 (-8825 2800);
DISPLAY INVISIBLE (-8825 2800);
FORCEPROP 1 LAST OFFPAGE TRUE
J 0
(-8500 2675);
DISPLAY 0.872340 (-8500 2675);
PAINT GREEN (-8500 2675);
DISPLAY INVISIBLE (-8500 2675);
FORCEPROP 1 LAST COMMENT_BODY TRUE
J 0
(-8725 2725);
DISPLAY 0.872340 (-8725 2725);
PAINT GREEN (-8725 2725);
DISPLAY INVISIBLE (-8725 2725);
FORCEPROP 2 LAST PATH I244
J 0
(-9050 2850);
DISPLAY 0.680851 (-9050 2850);
DISPLAY INVISIBLE (-9050 2850);
FORCEADD TAP..1
R 2
(-7700 3300);
FORCEPROP 3 LASTPIN (-7650 3300) SIG_NAME M_I_CPU0_SB_CB<1>
J 0
(-7640 3310);
DISPLAY 0.659574 (-7640 3310);
PAINT MONO (-7640 3310);
DISPLAY INVISIBLE (-7640 3310);
FORCEPROP 1 LASTPIN (-7650 3300) BN 1
J 2
(-7638 3308);
DISPLAY 0.489362 (-7638 3308);
PAINT GREEN (-7638 3308);
FORCEPROP 2 LAST CDS_LIB mstr_standard
J 0
(-7700 3300);
DISPLAY 0.723404 (-7700 3300);
PAINT MONO (-7700 3300);
DISPLAY INVISIBLE (-7700 3300);
FORCEPROP 1 LAST BODY_TYPE PLUMBING
J 2
(-7700 3350);
DISPLAY 0.872340 (-7700 3350);
PAINT GREEN (-7700 3350);
DISPLAY INVISIBLE (-7700 3350);
FORCEPROP 1 LAST HDL_TAP TRUE
J 2
(-8025 3175);
DISPLAY 0.872340 (-8025 3175);
DISPLAY INVISIBLE (-8025 3175);
FORCEPROP 1 LAST PATH I25
J 2
(-7698 3300);
DISPLAY 0.872340 (-7698 3300);
PAINT GREEN (-7698 3300);
DISPLAY INVISIBLE (-7698 3300);
FORCEADD TAP..1
R 2
(-7700 3250);
FORCEPROP 3 LASTPIN (-7650 3250) SIG_NAME M_I_CPU0_SB_CB<0>
J 0
(-7640 3260);
DISPLAY 0.659574 (-7640 3260);
PAINT MONO (-7640 3260);
DISPLAY INVISIBLE (-7640 3260);
FORCEPROP 1 LASTPIN (-7650 3250) BN 0
J 2
(-7638 3258);
DISPLAY 0.489362 (-7638 3258);
PAINT GREEN (-7638 3258);
FORCEPROP 2 LAST CDS_LIB mstr_standard
J 0
(-7700 3250);
DISPLAY 0.723404 (-7700 3250);
PAINT MONO (-7700 3250);
DISPLAY INVISIBLE (-7700 3250);
FORCEPROP 1 LAST BODY_TYPE PLUMBING
J 2
(-7700 3300);
DISPLAY 0.872340 (-7700 3300);
PAINT GREEN (-7700 3300);
DISPLAY INVISIBLE (-7700 3300);
FORCEPROP 1 LAST HDL_TAP TRUE
J 2
(-8025 3125);
DISPLAY 0.872340 (-8025 3125);
DISPLAY INVISIBLE (-8025 3125);
FORCEPROP 1 LAST PATH I26
J 2
(-7698 3250);
DISPLAY 0.872340 (-7698 3250);
PAINT GREEN (-7698 3250);
DISPLAY INVISIBLE (-7698 3250);
FORCEADD TAP..1
R 2
(-7700 3450);
FORCEPROP 3 LASTPIN (-7650 3450) SIG_NAME M_I_CPU0_SB_CB<4>
J 0
(-7640 3460);
DISPLAY 0.659574 (-7640 3460);
PAINT MONO (-7640 3460);
DISPLAY INVISIBLE (-7640 3460);
FORCEPROP 1 LASTPIN (-7650 3450) BN 4
J 2
(-7638 3458);
DISPLAY 0.489362 (-7638 3458);
PAINT GREEN (-7638 3458);
FORCEPROP 2 LAST CDS_LIB mstr_standard
J 0
(-7700 3450);
DISPLAY 0.723404 (-7700 3450);
PAINT MONO (-7700 3450);
DISPLAY INVISIBLE (-7700 3450);
FORCEPROP 1 LAST BODY_TYPE PLUMBING
J 2
(-7700 3500);
DISPLAY 0.872340 (-7700 3500);
PAINT GREEN (-7700 3500);
DISPLAY INVISIBLE (-7700 3500);
FORCEPROP 1 LAST HDL_TAP TRUE
J 2
(-8025 3325);
DISPLAY 0.872340 (-8025 3325);
DISPLAY INVISIBLE (-8025 3325);
FORCEPROP 1 LAST PATH I27
J 2
(-7698 3450);
DISPLAY 0.872340 (-7698 3450);
PAINT GREEN (-7698 3450);
DISPLAY INVISIBLE (-7698 3450);
FORCEADD TAP..1
R 2
(-7700 3500);
FORCEPROP 3 LASTPIN (-7650 3500) SIG_NAME M_I_CPU0_SB_CB<5>
J 0
(-7640 3510);
DISPLAY 0.659574 (-7640 3510);
PAINT MONO (-7640 3510);
DISPLAY INVISIBLE (-7640 3510);
FORCEPROP 1 LASTPIN (-7650 3500) BN 5
J 2
(-7638 3508);
DISPLAY 0.489362 (-7638 3508);
PAINT GREEN (-7638 3508);
FORCEPROP 2 LAST CDS_LIB mstr_standard
J 0
(-7700 3500);
DISPLAY 0.723404 (-7700 3500);
PAINT MONO (-7700 3500);
DISPLAY INVISIBLE (-7700 3500);
FORCEPROP 1 LAST BODY_TYPE PLUMBING
J 2
(-7700 3550);
DISPLAY 0.872340 (-7700 3550);
PAINT GREEN (-7700 3550);
DISPLAY INVISIBLE (-7700 3550);
FORCEPROP 1 LAST HDL_TAP TRUE
J 2
(-8025 3375);
DISPLAY 0.872340 (-8025 3375);
DISPLAY INVISIBLE (-8025 3375);
FORCEPROP 1 LAST PATH I28
J 2
(-7698 3500);
DISPLAY 0.872340 (-7698 3500);
PAINT GREEN (-7698 3500);
DISPLAY INVISIBLE (-7698 3500);
FORCEADD TAP..1
R 2
(-7700 3550);
FORCEPROP 3 LASTPIN (-7650 3550) SIG_NAME M_I_CPU0_SB_CB<6>
J 0
(-7640 3560);
DISPLAY 0.659574 (-7640 3560);
PAINT MONO (-7640 3560);
DISPLAY INVISIBLE (-7640 3560);
FORCEPROP 1 LASTPIN (-7650 3550) BN 6
J 2
(-7638 3558);
DISPLAY 0.489362 (-7638 3558);
PAINT GREEN (-7638 3558);
FORCEPROP 2 LAST CDS_LIB mstr_standard
J 0
(-7700 3550);
DISPLAY 0.723404 (-7700 3550);
PAINT MONO (-7700 3550);
DISPLAY INVISIBLE (-7700 3550);
FORCEPROP 1 LAST BODY_TYPE PLUMBING
J 2
(-7700 3600);
DISPLAY 0.872340 (-7700 3600);
PAINT GREEN (-7700 3600);
DISPLAY INVISIBLE (-7700 3600);
FORCEPROP 1 LAST HDL_TAP TRUE
J 2
(-8025 3425);
DISPLAY 0.872340 (-8025 3425);
DISPLAY INVISIBLE (-8025 3425);
FORCEPROP 1 LAST PATH I29
J 2
(-7698 3550);
DISPLAY 0.872340 (-7698 3550);
PAINT GREEN (-7698 3550);
DISPLAY INVISIBLE (-7698 3550);
FORCEADD TAP..1
R 2
(-7700 3600);
FORCEPROP 3 LASTPIN (-7650 3600) SIG_NAME M_I_CPU0_SB_CB<7>
J 0
(-7640 3610);
DISPLAY 0.659574 (-7640 3610);
PAINT MONO (-7640 3610);
DISPLAY INVISIBLE (-7640 3610);
FORCEPROP 1 LASTPIN (-7650 3600) BN 7
J 2
(-7638 3608);
DISPLAY 0.489362 (-7638 3608);
PAINT GREEN (-7638 3608);
FORCEPROP 2 LAST CDS_LIB mstr_standard
J 0
(-7700 3600);
DISPLAY 0.723404 (-7700 3600);
PAINT MONO (-7700 3600);
DISPLAY INVISIBLE (-7700 3600);
FORCEPROP 1 LAST BODY_TYPE PLUMBING
J 2
(-7700 3650);
DISPLAY 0.872340 (-7700 3650);
PAINT GREEN (-7700 3650);
DISPLAY INVISIBLE (-7700 3650);
FORCEPROP 1 LAST HDL_TAP TRUE
J 2
(-8025 3475);
DISPLAY 0.872340 (-8025 3475);
DISPLAY INVISIBLE (-8025 3475);
FORCEPROP 1 LAST PATH I30
J 2
(-7698 3600);
DISPLAY 0.872340 (-7698 3600);
PAINT GREEN (-7698 3600);
DISPLAY INVISIBLE (-7698 3600);
FORCEADD TAP..1
R 2
(-7700 3700);
FORCEPROP 3 LASTPIN (-7650 3700) SIG_NAME M_I_CPU0_SA_CB<0>
J 0
(-7640 3710);
DISPLAY 0.659574 (-7640 3710);
PAINT MONO (-7640 3710);
DISPLAY INVISIBLE (-7640 3710);
FORCEPROP 1 LASTPIN (-7650 3700) BN 0
J 2
(-7638 3708);
DISPLAY 0.489362 (-7638 3708);
PAINT GREEN (-7638 3708);
FORCEPROP 2 LAST CDS_LIB mstr_standard
J 0
(-7700 3700);
DISPLAY 0.723404 (-7700 3700);
PAINT MONO (-7700 3700);
DISPLAY INVISIBLE (-7700 3700);
FORCEPROP 1 LAST BODY_TYPE PLUMBING
J 2
(-7700 3750);
DISPLAY 0.872340 (-7700 3750);
PAINT GREEN (-7700 3750);
DISPLAY INVISIBLE (-7700 3750);
FORCEPROP 1 LAST HDL_TAP TRUE
J 2
(-8025 3575);
DISPLAY 0.872340 (-8025 3575);
DISPLAY INVISIBLE (-8025 3575);
FORCEPROP 1 LAST PATH I31
J 2
(-7698 3700);
DISPLAY 0.872340 (-7698 3700);
PAINT GREEN (-7698 3700);
DISPLAY INVISIBLE (-7698 3700);
FORCEADD TAP..1
R 2
(-7700 3750);
FORCEPROP 3 LASTPIN (-7650 3750) SIG_NAME M_I_CPU0_SA_CB<1>
J 0
(-7640 3760);
DISPLAY 0.659574 (-7640 3760);
PAINT MONO (-7640 3760);
DISPLAY INVISIBLE (-7640 3760);
FORCEPROP 1 LASTPIN (-7650 3750) BN 1
J 2
(-7638 3758);
DISPLAY 0.489362 (-7638 3758);
PAINT GREEN (-7638 3758);
FORCEPROP 2 LAST CDS_LIB mstr_standard
J 0
(-7700 3750);
DISPLAY 0.723404 (-7700 3750);
PAINT MONO (-7700 3750);
DISPLAY INVISIBLE (-7700 3750);
FORCEPROP 1 LAST BODY_TYPE PLUMBING
J 2
(-7700 3800);
DISPLAY 0.872340 (-7700 3800);
PAINT GREEN (-7700 3800);
DISPLAY INVISIBLE (-7700 3800);
FORCEPROP 1 LAST HDL_TAP TRUE
J 2
(-8025 3625);
DISPLAY 0.872340 (-8025 3625);
DISPLAY INVISIBLE (-8025 3625);
FORCEPROP 1 LAST PATH I32
J 2
(-7698 3750);
DISPLAY 0.872340 (-7698 3750);
PAINT GREEN (-7698 3750);
DISPLAY INVISIBLE (-7698 3750);
FORCEADD TAP..1
R 2
(-7700 3800);
FORCEPROP 3 LASTPIN (-7650 3800) SIG_NAME M_I_CPU0_SA_CB<2>
J 0
(-7640 3810);
DISPLAY 0.659574 (-7640 3810);
PAINT MONO (-7640 3810);
DISPLAY INVISIBLE (-7640 3810);
FORCEPROP 1 LASTPIN (-7650 3800) BN 2
J 2
(-7638 3808);
DISPLAY 0.489362 (-7638 3808);
PAINT GREEN (-7638 3808);
FORCEPROP 2 LAST CDS_LIB mstr_standard
J 0
(-7700 3800);
DISPLAY 0.723404 (-7700 3800);
PAINT MONO (-7700 3800);
DISPLAY INVISIBLE (-7700 3800);
FORCEPROP 1 LAST BODY_TYPE PLUMBING
J 2
(-7700 3850);
DISPLAY 0.872340 (-7700 3850);
PAINT GREEN (-7700 3850);
DISPLAY INVISIBLE (-7700 3850);
FORCEPROP 1 LAST HDL_TAP TRUE
J 2
(-8025 3675);
DISPLAY 0.872340 (-8025 3675);
DISPLAY INVISIBLE (-8025 3675);
FORCEPROP 1 LAST PATH I33
J 2
(-7698 3800);
DISPLAY 0.872340 (-7698 3800);
PAINT GREEN (-7698 3800);
DISPLAY INVISIBLE (-7698 3800);
FORCEADD TAP..1
R 2
(-7700 3850);
FORCEPROP 3 LASTPIN (-7650 3850) SIG_NAME M_I_CPU0_SA_CB<3>
J 0
(-7640 3860);
DISPLAY 0.659574 (-7640 3860);
PAINT MONO (-7640 3860);
DISPLAY INVISIBLE (-7640 3860);
FORCEPROP 1 LASTPIN (-7650 3850) BN 3
J 2
(-7638 3858);
DISPLAY 0.489362 (-7638 3858);
PAINT GREEN (-7638 3858);
FORCEPROP 2 LAST CDS_LIB mstr_standard
J 0
(-7700 3850);
DISPLAY 0.723404 (-7700 3850);
PAINT MONO (-7700 3850);
DISPLAY INVISIBLE (-7700 3850);
FORCEPROP 1 LAST BODY_TYPE PLUMBING
J 2
(-7700 3900);
DISPLAY 0.872340 (-7700 3900);
PAINT GREEN (-7700 3900);
DISPLAY INVISIBLE (-7700 3900);
FORCEPROP 1 LAST HDL_TAP TRUE
J 2
(-8025 3725);
DISPLAY 0.872340 (-8025 3725);
DISPLAY INVISIBLE (-8025 3725);
FORCEPROP 1 LAST PATH I34
J 2
(-7698 3850);
DISPLAY 0.872340 (-7698 3850);
PAINT GREEN (-7698 3850);
DISPLAY INVISIBLE (-7698 3850);
FORCEADD TAP..1
R 2
(-7700 3900);
FORCEPROP 3 LASTPIN (-7650 3900) SIG_NAME M_I_CPU0_SA_CB<4>
J 0
(-7640 3910);
DISPLAY 0.659574 (-7640 3910);
PAINT MONO (-7640 3910);
DISPLAY INVISIBLE (-7640 3910);
FORCEPROP 1 LASTPIN (-7650 3900) BN 4
J 2
(-7638 3908);
DISPLAY 0.489362 (-7638 3908);
PAINT GREEN (-7638 3908);
FORCEPROP 2 LAST CDS_LIB mstr_standard
J 0
(-7700 3900);
DISPLAY 0.723404 (-7700 3900);
PAINT MONO (-7700 3900);
DISPLAY INVISIBLE (-7700 3900);
FORCEPROP 1 LAST BODY_TYPE PLUMBING
J 2
(-7700 3950);
DISPLAY 0.872340 (-7700 3950);
PAINT GREEN (-7700 3950);
DISPLAY INVISIBLE (-7700 3950);
FORCEPROP 1 LAST HDL_TAP TRUE
J 2
(-8025 3775);
DISPLAY 0.872340 (-8025 3775);
DISPLAY INVISIBLE (-8025 3775);
FORCEPROP 1 LAST PATH I35
J 2
(-7698 3900);
DISPLAY 0.872340 (-7698 3900);
PAINT GREEN (-7698 3900);
DISPLAY INVISIBLE (-7698 3900);
FORCEADD TAP..1
(-6000 2250);
FORCEPROP 3 LASTPIN (-6050 2250) SIG_NAME M_I_CPU0_SB_DQ<0>
J 0
(-6040 2260);
DISPLAY 0.659574 (-6040 2260);
PAINT MONO (-6040 2260);
DISPLAY INVISIBLE (-6040 2260);
FORCEPROP 1 LASTPIN (-6050 2250) BN 0
J 0
(-6062 2258);
DISPLAY 0.489362 (-6062 2258);
PAINT GREEN (-6062 2258);
FORCEPROP 2 LAST CDS_LIB mstr_standard
J 0
(-6000 2250);
DISPLAY 0.723404 (-6000 2250);
PAINT MONO (-6000 2250);
DISPLAY INVISIBLE (-6000 2250);
FORCEPROP 1 LAST BODY_TYPE PLUMBING
J 0
(-6000 2300);
DISPLAY 0.872340 (-6000 2300);
PAINT GREEN (-6000 2300);
DISPLAY INVISIBLE (-6000 2300);
FORCEPROP 1 LAST HDL_TAP TRUE
J 0
(-5675 2125);
DISPLAY 0.872340 (-5675 2125);
DISPLAY INVISIBLE (-5675 2125);
FORCEPROP 1 LAST PATH I36
J 0
(-6002 2250);
DISPLAY 0.872340 (-6002 2250);
PAINT GREEN (-6002 2250);
DISPLAY INVISIBLE (-6002 2250);
FORCEADD TAP..1
(-6000 2350);
FORCEPROP 3 LASTPIN (-6050 2350) SIG_NAME M_I_CPU0_SB_DQ<2>
J 0
(-6040 2360);
DISPLAY 0.659574 (-6040 2360);
PAINT MONO (-6040 2360);
DISPLAY INVISIBLE (-6040 2360);
FORCEPROP 1 LASTPIN (-6050 2350) BN 2
J 0
(-6062 2358);
DISPLAY 0.489362 (-6062 2358);
PAINT GREEN (-6062 2358);
FORCEPROP 2 LAST CDS_LIB mstr_standard
J 0
(-6000 2350);
DISPLAY 0.723404 (-6000 2350);
PAINT MONO (-6000 2350);
DISPLAY INVISIBLE (-6000 2350);
FORCEPROP 1 LAST BODY_TYPE PLUMBING
J 0
(-6000 2400);
DISPLAY 0.872340 (-6000 2400);
PAINT GREEN (-6000 2400);
DISPLAY INVISIBLE (-6000 2400);
FORCEPROP 1 LAST HDL_TAP TRUE
J 0
(-5675 2225);
DISPLAY 0.872340 (-5675 2225);
DISPLAY INVISIBLE (-5675 2225);
FORCEPROP 1 LAST PATH I37
J 0
(-6002 2350);
DISPLAY 0.872340 (-6002 2350);
PAINT GREEN (-6002 2350);
DISPLAY INVISIBLE (-6002 2350);
FORCEADD TAP..1
(-6000 2400);
FORCEPROP 3 LASTPIN (-6050 2400) SIG_NAME M_I_CPU0_SB_DQ<3>
J 0
(-6040 2410);
DISPLAY 0.659574 (-6040 2410);
PAINT MONO (-6040 2410);
DISPLAY INVISIBLE (-6040 2410);
FORCEPROP 1 LASTPIN (-6050 2400) BN 3
J 0
(-6062 2408);
DISPLAY 0.489362 (-6062 2408);
PAINT GREEN (-6062 2408);
FORCEPROP 2 LAST CDS_LIB mstr_standard
J 0
(-6000 2400);
DISPLAY 0.723404 (-6000 2400);
PAINT MONO (-6000 2400);
DISPLAY INVISIBLE (-6000 2400);
FORCEPROP 1 LAST BODY_TYPE PLUMBING
J 0
(-6000 2450);
DISPLAY 0.872340 (-6000 2450);
PAINT GREEN (-6000 2450);
DISPLAY INVISIBLE (-6000 2450);
FORCEPROP 1 LAST HDL_TAP TRUE
J 0
(-5675 2275);
DISPLAY 0.872340 (-5675 2275);
DISPLAY INVISIBLE (-5675 2275);
FORCEPROP 1 LAST PATH I38
J 0
(-6002 2400);
DISPLAY 0.872340 (-6002 2400);
PAINT GREEN (-6002 2400);
DISPLAY INVISIBLE (-6002 2400);
FORCEADD TAP..1
(-6000 2300);
FORCEPROP 3 LASTPIN (-6050 2300) SIG_NAME M_I_CPU0_SB_DQ<1>
J 0
(-6040 2310);
DISPLAY 0.659574 (-6040 2310);
PAINT MONO (-6040 2310);
DISPLAY INVISIBLE (-6040 2310);
FORCEPROP 1 LASTPIN (-6050 2300) BN 1
J 0
(-6062 2308);
DISPLAY 0.489362 (-6062 2308);
PAINT GREEN (-6062 2308);
FORCEPROP 2 LAST CDS_LIB mstr_standard
J 0
(-6000 2300);
DISPLAY 0.723404 (-6000 2300);
PAINT MONO (-6000 2300);
DISPLAY INVISIBLE (-6000 2300);
FORCEPROP 1 LAST BODY_TYPE PLUMBING
J 0
(-6000 2350);
DISPLAY 0.872340 (-6000 2350);
PAINT GREEN (-6000 2350);
DISPLAY INVISIBLE (-6000 2350);
FORCEPROP 1 LAST HDL_TAP TRUE
J 0
(-5675 2175);
DISPLAY 0.872340 (-5675 2175);
DISPLAY INVISIBLE (-5675 2175);
FORCEPROP 1 LAST PATH I39
J 0
(-6002 2300);
DISPLAY 0.872340 (-6002 2300);
PAINT GREEN (-6002 2300);
DISPLAY INVISIBLE (-6002 2300);
FORCEADD TAP..1
(-6000 2450);
FORCEPROP 3 LASTPIN (-6050 2450) SIG_NAME M_I_CPU0_SB_DQ<4>
J 0
(-6040 2460);
DISPLAY 0.659574 (-6040 2460);
PAINT MONO (-6040 2460);
DISPLAY INVISIBLE (-6040 2460);
FORCEPROP 1 LASTPIN (-6050 2450) BN 4
J 0
(-6062 2458);
DISPLAY 0.489362 (-6062 2458);
PAINT GREEN (-6062 2458);
FORCEPROP 2 LAST CDS_LIB mstr_standard
J 0
(-6000 2450);
DISPLAY 0.723404 (-6000 2450);
PAINT MONO (-6000 2450);
DISPLAY INVISIBLE (-6000 2450);
FORCEPROP 1 LAST BODY_TYPE PLUMBING
J 0
(-6000 2500);
DISPLAY 0.872340 (-6000 2500);
PAINT GREEN (-6000 2500);
DISPLAY INVISIBLE (-6000 2500);
FORCEPROP 1 LAST HDL_TAP TRUE
J 0
(-5675 2325);
DISPLAY 0.872340 (-5675 2325);
DISPLAY INVISIBLE (-5675 2325);
FORCEPROP 1 LAST PATH I40
J 0
(-6002 2450);
DISPLAY 0.872340 (-6002 2450);
PAINT GREEN (-6002 2450);
DISPLAY INVISIBLE (-6002 2450);
FORCEADD TAP..1
(-6000 2500);
FORCEPROP 3 LASTPIN (-6050 2500) SIG_NAME M_I_CPU0_SB_DQ<5>
J 0
(-6040 2510);
DISPLAY 0.659574 (-6040 2510);
PAINT MONO (-6040 2510);
DISPLAY INVISIBLE (-6040 2510);
FORCEPROP 1 LASTPIN (-6050 2500) BN 5
J 0
(-6062 2508);
DISPLAY 0.489362 (-6062 2508);
PAINT GREEN (-6062 2508);
FORCEPROP 2 LAST CDS_LIB mstr_standard
J 0
(-6000 2500);
DISPLAY 0.723404 (-6000 2500);
PAINT MONO (-6000 2500);
DISPLAY INVISIBLE (-6000 2500);
FORCEPROP 1 LAST BODY_TYPE PLUMBING
J 0
(-6000 2550);
DISPLAY 0.872340 (-6000 2550);
PAINT GREEN (-6000 2550);
DISPLAY INVISIBLE (-6000 2550);
FORCEPROP 1 LAST HDL_TAP TRUE
J 0
(-5675 2375);
DISPLAY 0.872340 (-5675 2375);
DISPLAY INVISIBLE (-5675 2375);
FORCEPROP 1 LAST PATH I41
J 0
(-6002 2500);
DISPLAY 0.872340 (-6002 2500);
PAINT GREEN (-6002 2500);
DISPLAY INVISIBLE (-6002 2500);
FORCEADD TAP..1
(-6000 2550);
FORCEPROP 3 LASTPIN (-6050 2550) SIG_NAME M_I_CPU0_SB_DQ<6>
J 0
(-6040 2560);
DISPLAY 0.659574 (-6040 2560);
PAINT MONO (-6040 2560);
DISPLAY INVISIBLE (-6040 2560);
FORCEPROP 1 LASTPIN (-6050 2550) BN 6
J 0
(-6062 2558);
DISPLAY 0.489362 (-6062 2558);
PAINT GREEN (-6062 2558);
FORCEPROP 2 LAST CDS_LIB mstr_standard
J 0
(-6000 2550);
DISPLAY 0.723404 (-6000 2550);
PAINT MONO (-6000 2550);
DISPLAY INVISIBLE (-6000 2550);
FORCEPROP 1 LAST BODY_TYPE PLUMBING
J 0
(-6000 2600);
DISPLAY 0.872340 (-6000 2600);
PAINT GREEN (-6000 2600);
DISPLAY INVISIBLE (-6000 2600);
FORCEPROP 1 LAST HDL_TAP TRUE
J 0
(-5675 2425);
DISPLAY 0.872340 (-5675 2425);
DISPLAY INVISIBLE (-5675 2425);
FORCEPROP 1 LAST PATH I42
J 0
(-6002 2550);
DISPLAY 0.872340 (-6002 2550);
PAINT GREEN (-6002 2550);
DISPLAY INVISIBLE (-6002 2550);
FORCEADD TAP..1
(-6000 2600);
FORCEPROP 3 LASTPIN (-6050 2600) SIG_NAME M_I_CPU0_SB_DQ<7>
J 0
(-6040 2610);
DISPLAY 0.659574 (-6040 2610);
PAINT MONO (-6040 2610);
DISPLAY INVISIBLE (-6040 2610);
FORCEPROP 1 LASTPIN (-6050 2600) BN 7
J 0
(-6062 2608);
DISPLAY 0.489362 (-6062 2608);
PAINT GREEN (-6062 2608);
FORCEPROP 2 LAST CDS_LIB mstr_standard
J 0
(-6000 2600);
DISPLAY 0.723404 (-6000 2600);
PAINT MONO (-6000 2600);
DISPLAY INVISIBLE (-6000 2600);
FORCEPROP 1 LAST BODY_TYPE PLUMBING
J 0
(-6000 2650);
DISPLAY 0.872340 (-6000 2650);
PAINT GREEN (-6000 2650);
DISPLAY INVISIBLE (-6000 2650);
FORCEPROP 1 LAST HDL_TAP TRUE
J 0
(-5675 2475);
DISPLAY 0.872340 (-5675 2475);
DISPLAY INVISIBLE (-5675 2475);
FORCEPROP 1 LAST PATH I43
J 0
(-6002 2600);
DISPLAY 0.872340 (-6002 2600);
PAINT GREEN (-6002 2600);
DISPLAY INVISIBLE (-6002 2600);
FORCEADD TAP..1
(-6000 2650);
FORCEPROP 3 LASTPIN (-6050 2650) SIG_NAME M_I_CPU0_SB_DQ<8>
J 0
(-6040 2660);
DISPLAY 0.659574 (-6040 2660);
PAINT MONO (-6040 2660);
DISPLAY INVISIBLE (-6040 2660);
FORCEPROP 1 LASTPIN (-6050 2650) BN 8
J 0
(-6062 2658);
DISPLAY 0.489362 (-6062 2658);
PAINT GREEN (-6062 2658);
FORCEPROP 2 LAST CDS_LIB mstr_standard
J 0
(-6000 2650);
DISPLAY 0.723404 (-6000 2650);
PAINT MONO (-6000 2650);
DISPLAY INVISIBLE (-6000 2650);
FORCEPROP 1 LAST BODY_TYPE PLUMBING
J 0
(-6000 2700);
DISPLAY 0.872340 (-6000 2700);
PAINT GREEN (-6000 2700);
DISPLAY INVISIBLE (-6000 2700);
FORCEPROP 1 LAST HDL_TAP TRUE
J 0
(-5675 2525);
DISPLAY 0.872340 (-5675 2525);
DISPLAY INVISIBLE (-5675 2525);
FORCEPROP 1 LAST PATH I44
J 0
(-6002 2650);
DISPLAY 0.872340 (-6002 2650);
PAINT GREEN (-6002 2650);
DISPLAY INVISIBLE (-6002 2650);
FORCEADD TAP..1
(-6000 2700);
FORCEPROP 3 LASTPIN (-6050 2700) SIG_NAME M_I_CPU0_SB_DQ<9>
J 0
(-6040 2710);
DISPLAY 0.659574 (-6040 2710);
PAINT MONO (-6040 2710);
DISPLAY INVISIBLE (-6040 2710);
FORCEPROP 1 LASTPIN (-6050 2700) BN 9
J 0
(-6062 2708);
DISPLAY 0.489362 (-6062 2708);
PAINT GREEN (-6062 2708);
FORCEPROP 2 LAST CDS_LIB mstr_standard
J 0
(-6000 2700);
DISPLAY 0.723404 (-6000 2700);
PAINT MONO (-6000 2700);
DISPLAY INVISIBLE (-6000 2700);
FORCEPROP 1 LAST BODY_TYPE PLUMBING
J 0
(-6000 2750);
DISPLAY 0.872340 (-6000 2750);
PAINT GREEN (-6000 2750);
DISPLAY INVISIBLE (-6000 2750);
FORCEPROP 1 LAST HDL_TAP TRUE
J 0
(-5675 2575);
DISPLAY 0.872340 (-5675 2575);
DISPLAY INVISIBLE (-5675 2575);
FORCEPROP 1 LAST PATH I45
J 0
(-6002 2700);
DISPLAY 0.872340 (-6002 2700);
PAINT GREEN (-6002 2700);
DISPLAY INVISIBLE (-6002 2700);
FORCEADD TAP..1
(-6000 2750);
FORCEPROP 3 LASTPIN (-6050 2750) SIG_NAME M_I_CPU0_SB_DQ<10>
J 0
(-6040 2760);
DISPLAY 0.659574 (-6040 2760);
PAINT MONO (-6040 2760);
DISPLAY INVISIBLE (-6040 2760);
FORCEPROP 1 LASTPIN (-6050 2750) BN 10
J 0
(-6062 2758);
DISPLAY 0.489362 (-6062 2758);
PAINT GREEN (-6062 2758);
FORCEPROP 2 LAST CDS_LIB mstr_standard
J 0
(-6000 2750);
DISPLAY 0.723404 (-6000 2750);
PAINT MONO (-6000 2750);
DISPLAY INVISIBLE (-6000 2750);
FORCEPROP 1 LAST BODY_TYPE PLUMBING
J 0
(-6000 2800);
DISPLAY 0.872340 (-6000 2800);
PAINT GREEN (-6000 2800);
DISPLAY INVISIBLE (-6000 2800);
FORCEPROP 1 LAST HDL_TAP TRUE
J 0
(-5675 2625);
DISPLAY 0.872340 (-5675 2625);
DISPLAY INVISIBLE (-5675 2625);
FORCEPROP 1 LAST PATH I46
J 0
(-6002 2750);
DISPLAY 0.872340 (-6002 2750);
PAINT GREEN (-6002 2750);
DISPLAY INVISIBLE (-6002 2750);
FORCEADD TAP..1
(-6000 2800);
FORCEPROP 3 LASTPIN (-6050 2800) SIG_NAME M_I_CPU0_SB_DQ<11>
J 0
(-6040 2810);
DISPLAY 0.659574 (-6040 2810);
PAINT MONO (-6040 2810);
DISPLAY INVISIBLE (-6040 2810);
FORCEPROP 1 LASTPIN (-6050 2800) BN 11
J 0
(-6062 2808);
DISPLAY 0.489362 (-6062 2808);
PAINT GREEN (-6062 2808);
FORCEPROP 2 LAST CDS_LIB mstr_standard
J 0
(-6000 2800);
DISPLAY 0.723404 (-6000 2800);
PAINT MONO (-6000 2800);
DISPLAY INVISIBLE (-6000 2800);
FORCEPROP 1 LAST BODY_TYPE PLUMBING
J 0
(-6000 2850);
DISPLAY 0.872340 (-6000 2850);
PAINT GREEN (-6000 2850);
DISPLAY INVISIBLE (-6000 2850);
FORCEPROP 1 LAST HDL_TAP TRUE
J 0
(-5675 2675);
DISPLAY 0.872340 (-5675 2675);
DISPLAY INVISIBLE (-5675 2675);
FORCEPROP 1 LAST PATH I47
J 0
(-6002 2800);
DISPLAY 0.872340 (-6002 2800);
PAINT GREEN (-6002 2800);
DISPLAY INVISIBLE (-6002 2800);
FORCEADD TAP..1
(-6000 2900);
FORCEPROP 3 LASTPIN (-6050 2900) SIG_NAME M_I_CPU0_SB_DQ<13>
J 0
(-6040 2910);
DISPLAY 0.659574 (-6040 2910);
PAINT MONO (-6040 2910);
DISPLAY INVISIBLE (-6040 2910);
FORCEPROP 1 LASTPIN (-6050 2900) BN 13
J 0
(-6062 2908);
DISPLAY 0.489362 (-6062 2908);
PAINT GREEN (-6062 2908);
FORCEPROP 2 LAST CDS_LIB mstr_standard
J 0
(-6000 2900);
DISPLAY 0.723404 (-6000 2900);
PAINT MONO (-6000 2900);
DISPLAY INVISIBLE (-6000 2900);
FORCEPROP 1 LAST BODY_TYPE PLUMBING
J 0
(-6000 2950);
DISPLAY 0.872340 (-6000 2950);
PAINT GREEN (-6000 2950);
DISPLAY INVISIBLE (-6000 2950);
FORCEPROP 1 LAST HDL_TAP TRUE
J 0
(-5675 2775);
DISPLAY 0.872340 (-5675 2775);
DISPLAY INVISIBLE (-5675 2775);
FORCEPROP 1 LAST PATH I48
J 0
(-6002 2900);
DISPLAY 0.872340 (-6002 2900);
PAINT GREEN (-6002 2900);
DISPLAY INVISIBLE (-6002 2900);
FORCEADD TAP..1
(-6000 2850);
FORCEPROP 3 LASTPIN (-6050 2850) SIG_NAME M_I_CPU0_SB_DQ<12>
J 0
(-6040 2860);
DISPLAY 0.659574 (-6040 2860);
PAINT MONO (-6040 2860);
DISPLAY INVISIBLE (-6040 2860);
FORCEPROP 1 LASTPIN (-6050 2850) BN 12
J 0
(-6062 2858);
DISPLAY 0.489362 (-6062 2858);
PAINT GREEN (-6062 2858);
FORCEPROP 2 LAST CDS_LIB mstr_standard
J 0
(-6000 2850);
DISPLAY 0.723404 (-6000 2850);
PAINT MONO (-6000 2850);
DISPLAY INVISIBLE (-6000 2850);
FORCEPROP 1 LAST BODY_TYPE PLUMBING
J 0
(-6000 2900);
DISPLAY 0.872340 (-6000 2900);
PAINT GREEN (-6000 2900);
DISPLAY INVISIBLE (-6000 2900);
FORCEPROP 1 LAST HDL_TAP TRUE
J 0
(-5675 2725);
DISPLAY 0.872340 (-5675 2725);
DISPLAY INVISIBLE (-5675 2725);
FORCEPROP 1 LAST PATH I49
J 0
(-6002 2850);
DISPLAY 0.872340 (-6002 2850);
PAINT GREEN (-6002 2850);
DISPLAY INVISIBLE (-6002 2850);
FORCEADD TAP..1
(-6000 2950);
FORCEPROP 3 LASTPIN (-6050 2950) SIG_NAME M_I_CPU0_SB_DQ<14>
J 0
(-6040 2960);
DISPLAY 0.659574 (-6040 2960);
PAINT MONO (-6040 2960);
DISPLAY INVISIBLE (-6040 2960);
FORCEPROP 1 LASTPIN (-6050 2950) BN 14
J 0
(-6062 2958);
DISPLAY 0.489362 (-6062 2958);
PAINT GREEN (-6062 2958);
FORCEPROP 2 LAST CDS_LIB mstr_standard
J 0
(-6000 2950);
DISPLAY 0.723404 (-6000 2950);
PAINT MONO (-6000 2950);
DISPLAY INVISIBLE (-6000 2950);
FORCEPROP 1 LAST BODY_TYPE PLUMBING
J 0
(-6000 3000);
DISPLAY 0.872340 (-6000 3000);
PAINT GREEN (-6000 3000);
DISPLAY INVISIBLE (-6000 3000);
FORCEPROP 1 LAST HDL_TAP TRUE
J 0
(-5675 2825);
DISPLAY 0.872340 (-5675 2825);
DISPLAY INVISIBLE (-5675 2825);
FORCEPROP 1 LAST PATH I50
J 0
(-6002 2950);
DISPLAY 0.872340 (-6002 2950);
PAINT GREEN (-6002 2950);
DISPLAY INVISIBLE (-6002 2950);
FORCEADD TAP..1
(-6000 3000);
FORCEPROP 3 LASTPIN (-6050 3000) SIG_NAME M_I_CPU0_SB_DQ<15>
J 0
(-6040 3010);
DISPLAY 0.659574 (-6040 3010);
PAINT MONO (-6040 3010);
DISPLAY INVISIBLE (-6040 3010);
FORCEPROP 1 LASTPIN (-6050 3000) BN 15
J 0
(-6062 3008);
DISPLAY 0.489362 (-6062 3008);
PAINT GREEN (-6062 3008);
FORCEPROP 2 LAST CDS_LIB mstr_standard
J 0
(-6000 3000);
DISPLAY 0.723404 (-6000 3000);
PAINT MONO (-6000 3000);
DISPLAY INVISIBLE (-6000 3000);
FORCEPROP 1 LAST BODY_TYPE PLUMBING
J 0
(-6000 3050);
DISPLAY 0.872340 (-6000 3050);
PAINT GREEN (-6000 3050);
DISPLAY INVISIBLE (-6000 3050);
FORCEPROP 1 LAST HDL_TAP TRUE
J 0
(-5675 2875);
DISPLAY 0.872340 (-5675 2875);
DISPLAY INVISIBLE (-5675 2875);
FORCEPROP 1 LAST PATH I51
J 0
(-6002 3000);
DISPLAY 0.872340 (-6002 3000);
PAINT GREEN (-6002 3000);
DISPLAY INVISIBLE (-6002 3000);
FORCEADD TAP..1
(-6000 3050);
FORCEPROP 3 LASTPIN (-6050 3050) SIG_NAME M_I_CPU0_SB_DQ<16>
J 0
(-6040 3060);
DISPLAY 0.659574 (-6040 3060);
PAINT MONO (-6040 3060);
DISPLAY INVISIBLE (-6040 3060);
FORCEPROP 1 LASTPIN (-6050 3050) BN 16
J 0
(-6062 3058);
DISPLAY 0.489362 (-6062 3058);
PAINT GREEN (-6062 3058);
FORCEPROP 2 LAST CDS_LIB mstr_standard
J 0
(-6000 3050);
DISPLAY 0.723404 (-6000 3050);
PAINT MONO (-6000 3050);
DISPLAY INVISIBLE (-6000 3050);
FORCEPROP 1 LAST BODY_TYPE PLUMBING
J 0
(-6000 3100);
DISPLAY 0.872340 (-6000 3100);
PAINT GREEN (-6000 3100);
DISPLAY INVISIBLE (-6000 3100);
FORCEPROP 1 LAST HDL_TAP TRUE
J 0
(-5675 2925);
DISPLAY 0.872340 (-5675 2925);
DISPLAY INVISIBLE (-5675 2925);
FORCEPROP 1 LAST PATH I52
J 0
(-6002 3050);
DISPLAY 0.872340 (-6002 3050);
PAINT GREEN (-6002 3050);
DISPLAY INVISIBLE (-6002 3050);
FORCEADD TAP..1
(-6000 3100);
FORCEPROP 3 LASTPIN (-6050 3100) SIG_NAME M_I_CPU0_SB_DQ<17>
J 0
(-6040 3110);
DISPLAY 0.659574 (-6040 3110);
PAINT MONO (-6040 3110);
DISPLAY INVISIBLE (-6040 3110);
FORCEPROP 1 LASTPIN (-6050 3100) BN 17
J 0
(-6062 3108);
DISPLAY 0.489362 (-6062 3108);
PAINT GREEN (-6062 3108);
FORCEPROP 2 LAST CDS_LIB mstr_standard
J 0
(-6000 3100);
DISPLAY 0.723404 (-6000 3100);
PAINT MONO (-6000 3100);
DISPLAY INVISIBLE (-6000 3100);
FORCEPROP 1 LAST BODY_TYPE PLUMBING
J 0
(-6000 3150);
DISPLAY 0.872340 (-6000 3150);
PAINT GREEN (-6000 3150);
DISPLAY INVISIBLE (-6000 3150);
FORCEPROP 1 LAST HDL_TAP TRUE
J 0
(-5675 2975);
DISPLAY 0.872340 (-5675 2975);
DISPLAY INVISIBLE (-5675 2975);
FORCEPROP 1 LAST PATH I53
J 0
(-6002 3100);
DISPLAY 0.872340 (-6002 3100);
PAINT GREEN (-6002 3100);
DISPLAY INVISIBLE (-6002 3100);
FORCEADD TAP..1
(-6000 3150);
FORCEPROP 3 LASTPIN (-6050 3150) SIG_NAME M_I_CPU0_SB_DQ<18>
J 0
(-6040 3160);
DISPLAY 0.659574 (-6040 3160);
PAINT MONO (-6040 3160);
DISPLAY INVISIBLE (-6040 3160);
FORCEPROP 1 LASTPIN (-6050 3150) BN 18
J 0
(-6062 3158);
DISPLAY 0.489362 (-6062 3158);
PAINT GREEN (-6062 3158);
FORCEPROP 2 LAST CDS_LIB mstr_standard
J 0
(-6000 3150);
DISPLAY 0.723404 (-6000 3150);
PAINT MONO (-6000 3150);
DISPLAY INVISIBLE (-6000 3150);
FORCEPROP 1 LAST BODY_TYPE PLUMBING
J 0
(-6000 3200);
DISPLAY 0.872340 (-6000 3200);
PAINT GREEN (-6000 3200);
DISPLAY INVISIBLE (-6000 3200);
FORCEPROP 1 LAST HDL_TAP TRUE
J 0
(-5675 3025);
DISPLAY 0.872340 (-5675 3025);
DISPLAY INVISIBLE (-5675 3025);
FORCEPROP 1 LAST PATH I54
J 0
(-6002 3150);
DISPLAY 0.872340 (-6002 3150);
PAINT GREEN (-6002 3150);
DISPLAY INVISIBLE (-6002 3150);
FORCEADD TAP..1
(-6000 3200);
FORCEPROP 3 LASTPIN (-6050 3200) SIG_NAME M_I_CPU0_SB_DQ<19>
J 0
(-6040 3210);
DISPLAY 0.659574 (-6040 3210);
PAINT MONO (-6040 3210);
DISPLAY INVISIBLE (-6040 3210);
FORCEPROP 1 LASTPIN (-6050 3200) BN 19
J 0
(-6062 3208);
DISPLAY 0.489362 (-6062 3208);
PAINT GREEN (-6062 3208);
FORCEPROP 2 LAST CDS_LIB mstr_standard
J 0
(-6000 3200);
DISPLAY 0.723404 (-6000 3200);
PAINT MONO (-6000 3200);
DISPLAY INVISIBLE (-6000 3200);
FORCEPROP 1 LAST BODY_TYPE PLUMBING
J 0
(-6000 3250);
DISPLAY 0.872340 (-6000 3250);
PAINT GREEN (-6000 3250);
DISPLAY INVISIBLE (-6000 3250);
FORCEPROP 1 LAST HDL_TAP TRUE
J 0
(-5675 3075);
DISPLAY 0.872340 (-5675 3075);
DISPLAY INVISIBLE (-5675 3075);
FORCEPROP 1 LAST PATH I55
J 0
(-6002 3200);
DISPLAY 0.872340 (-6002 3200);
PAINT GREEN (-6002 3200);
DISPLAY INVISIBLE (-6002 3200);
FORCEADD TAP..1
(-6000 3250);
FORCEPROP 3 LASTPIN (-6050 3250) SIG_NAME M_I_CPU0_SB_DQ<20>
J 0
(-6040 3260);
DISPLAY 0.659574 (-6040 3260);
PAINT MONO (-6040 3260);
DISPLAY INVISIBLE (-6040 3260);
FORCEPROP 1 LASTPIN (-6050 3250) BN 20
J 0
(-6062 3258);
DISPLAY 0.489362 (-6062 3258);
PAINT GREEN (-6062 3258);
FORCEPROP 2 LAST CDS_LIB mstr_standard
J 0
(-6000 3250);
DISPLAY 0.723404 (-6000 3250);
PAINT MONO (-6000 3250);
DISPLAY INVISIBLE (-6000 3250);
FORCEPROP 1 LAST BODY_TYPE PLUMBING
J 0
(-6000 3300);
DISPLAY 0.872340 (-6000 3300);
PAINT GREEN (-6000 3300);
DISPLAY INVISIBLE (-6000 3300);
FORCEPROP 1 LAST HDL_TAP TRUE
J 0
(-5675 3125);
DISPLAY 0.872340 (-5675 3125);
DISPLAY INVISIBLE (-5675 3125);
FORCEPROP 1 LAST PATH I56
J 0
(-6002 3250);
DISPLAY 0.872340 (-6002 3250);
PAINT GREEN (-6002 3250);
DISPLAY INVISIBLE (-6002 3250);
FORCEADD TAP..1
(-6000 3300);
FORCEPROP 3 LASTPIN (-6050 3300) SIG_NAME M_I_CPU0_SB_DQ<21>
J 0
(-6040 3310);
DISPLAY 0.659574 (-6040 3310);
PAINT MONO (-6040 3310);
DISPLAY INVISIBLE (-6040 3310);
FORCEPROP 1 LASTPIN (-6050 3300) BN 21
J 0
(-6062 3308);
DISPLAY 0.489362 (-6062 3308);
PAINT GREEN (-6062 3308);
FORCEPROP 2 LAST CDS_LIB mstr_standard
J 0
(-6000 3300);
DISPLAY 0.723404 (-6000 3300);
PAINT MONO (-6000 3300);
DISPLAY INVISIBLE (-6000 3300);
FORCEPROP 1 LAST BODY_TYPE PLUMBING
J 0
(-6000 3350);
DISPLAY 0.872340 (-6000 3350);
PAINT GREEN (-6000 3350);
DISPLAY INVISIBLE (-6000 3350);
FORCEPROP 1 LAST HDL_TAP TRUE
J 0
(-5675 3175);
DISPLAY 0.872340 (-5675 3175);
DISPLAY INVISIBLE (-5675 3175);
FORCEPROP 1 LAST PATH I57
J 0
(-6002 3300);
DISPLAY 0.872340 (-6002 3300);
PAINT GREEN (-6002 3300);
DISPLAY INVISIBLE (-6002 3300);
FORCEADD TAP..1
(-6000 3350);
FORCEPROP 3 LASTPIN (-6050 3350) SIG_NAME M_I_CPU0_SB_DQ<22>
J 0
(-6040 3360);
DISPLAY 0.659574 (-6040 3360);
PAINT MONO (-6040 3360);
DISPLAY INVISIBLE (-6040 3360);
FORCEPROP 1 LASTPIN (-6050 3350) BN 22
J 0
(-6062 3358);
DISPLAY 0.489362 (-6062 3358);
PAINT GREEN (-6062 3358);
FORCEPROP 2 LAST CDS_LIB mstr_standard
J 0
(-6000 3350);
DISPLAY 0.723404 (-6000 3350);
PAINT MONO (-6000 3350);
DISPLAY INVISIBLE (-6000 3350);
FORCEPROP 1 LAST BODY_TYPE PLUMBING
J 0
(-6000 3400);
DISPLAY 0.872340 (-6000 3400);
PAINT GREEN (-6000 3400);
DISPLAY INVISIBLE (-6000 3400);
FORCEPROP 1 LAST HDL_TAP TRUE
J 0
(-5675 3225);
DISPLAY 0.872340 (-5675 3225);
DISPLAY INVISIBLE (-5675 3225);
FORCEPROP 1 LAST PATH I58
J 0
(-6002 3350);
DISPLAY 0.872340 (-6002 3350);
PAINT GREEN (-6002 3350);
DISPLAY INVISIBLE (-6002 3350);
FORCEADD TAP..1
(-6000 3400);
FORCEPROP 3 LASTPIN (-6050 3400) SIG_NAME M_I_CPU0_SB_DQ<23>
J 0
(-6040 3410);
DISPLAY 0.659574 (-6040 3410);
PAINT MONO (-6040 3410);
DISPLAY INVISIBLE (-6040 3410);
FORCEPROP 1 LASTPIN (-6050 3400) BN 23
J 0
(-6062 3408);
DISPLAY 0.489362 (-6062 3408);
PAINT GREEN (-6062 3408);
FORCEPROP 2 LAST CDS_LIB mstr_standard
J 0
(-6000 3400);
DISPLAY 0.723404 (-6000 3400);
PAINT MONO (-6000 3400);
DISPLAY INVISIBLE (-6000 3400);
FORCEPROP 1 LAST BODY_TYPE PLUMBING
J 0
(-6000 3450);
DISPLAY 0.872340 (-6000 3450);
PAINT GREEN (-6000 3450);
DISPLAY INVISIBLE (-6000 3450);
FORCEPROP 1 LAST HDL_TAP TRUE
J 0
(-5675 3275);
DISPLAY 0.872340 (-5675 3275);
DISPLAY INVISIBLE (-5675 3275);
FORCEPROP 1 LAST PATH I59
J 0
(-6002 3400);
DISPLAY 0.872340 (-6002 3400);
PAINT GREEN (-6002 3400);
DISPLAY INVISIBLE (-6002 3400);
FORCEADD OFFPAGE..1
(-8575 2950);
FORCEPROP 2 LAST $XR0 94 
J 0
(-8826 2950);
DISPLAY 0.638298 (-8826 2950);
PAINT MONO (-8826 2950);
FORCEPROP 2 LAST CDS_LIB mstr_standard
J 0
(-8575 2950);
DISPLAY 0.808511 (-8575 2950);
DISPLAY INVISIBLE (-8575 2950);
FORCEPROP 1 LAST OFFPAGE TRUE
J 0
(-8250 2825);
DISPLAY 0.872340 (-8250 2825);
PAINT GREEN (-8250 2825);
DISPLAY INVISIBLE (-8250 2825);
FORCEPROP 1 LAST COMMENT_BODY TRUE
J 0
(-8450 2850);
DISPLAY 0.872340 (-8450 2850);
PAINT GREEN (-8450 2850);
DISPLAY INVISIBLE (-8450 2850);
FORCEPROP 2 LAST PATH I6
J 0
(-8825 3000);
DISPLAY 1.021277 (-8825 3000);
DISPLAY INVISIBLE (-8825 3000);
FORCEADD TAP..1
(-6000 3450);
FORCEPROP 3 LASTPIN (-6050 3450) SIG_NAME M_I_CPU0_SB_DQ<24>
J 0
(-6040 3460);
DISPLAY 0.659574 (-6040 3460);
PAINT MONO (-6040 3460);
DISPLAY INVISIBLE (-6040 3460);
FORCEPROP 1 LASTPIN (-6050 3450) BN 24
J 0
(-6062 3458);
DISPLAY 0.489362 (-6062 3458);
PAINT GREEN (-6062 3458);
FORCEPROP 2 LAST CDS_LIB mstr_standard
J 0
(-6000 3450);
DISPLAY 0.723404 (-6000 3450);
PAINT MONO (-6000 3450);
DISPLAY INVISIBLE (-6000 3450);
FORCEPROP 1 LAST BODY_TYPE PLUMBING
J 0
(-6000 3500);
DISPLAY 0.872340 (-6000 3500);
PAINT GREEN (-6000 3500);
DISPLAY INVISIBLE (-6000 3500);
FORCEPROP 1 LAST HDL_TAP TRUE
J 0
(-5675 3325);
DISPLAY 0.872340 (-5675 3325);
DISPLAY INVISIBLE (-5675 3325);
FORCEPROP 1 LAST PATH I60
J 0
(-6002 3450);
DISPLAY 0.872340 (-6002 3450);
PAINT GREEN (-6002 3450);
DISPLAY INVISIBLE (-6002 3450);
FORCEADD TAP..1
(-6000 3500);
FORCEPROP 3 LASTPIN (-6050 3500) SIG_NAME M_I_CPU0_SB_DQ<25>
J 0
(-6040 3510);
DISPLAY 0.659574 (-6040 3510);
PAINT MONO (-6040 3510);
DISPLAY INVISIBLE (-6040 3510);
FORCEPROP 1 LASTPIN (-6050 3500) BN 25
J 0
(-6062 3508);
DISPLAY 0.489362 (-6062 3508);
PAINT GREEN (-6062 3508);
FORCEPROP 2 LAST CDS_LIB mstr_standard
J 0
(-6000 3500);
DISPLAY 0.723404 (-6000 3500);
PAINT MONO (-6000 3500);
DISPLAY INVISIBLE (-6000 3500);
FORCEPROP 1 LAST BODY_TYPE PLUMBING
J 0
(-6000 3550);
DISPLAY 0.872340 (-6000 3550);
PAINT GREEN (-6000 3550);
DISPLAY INVISIBLE (-6000 3550);
FORCEPROP 1 LAST HDL_TAP TRUE
J 0
(-5675 3375);
DISPLAY 0.872340 (-5675 3375);
DISPLAY INVISIBLE (-5675 3375);
FORCEPROP 1 LAST PATH I61
J 0
(-6002 3500);
DISPLAY 0.872340 (-6002 3500);
PAINT GREEN (-6002 3500);
DISPLAY INVISIBLE (-6002 3500);
FORCEADD TAP..1
(-6000 3550);
FORCEPROP 3 LASTPIN (-6050 3550) SIG_NAME M_I_CPU0_SB_DQ<26>
J 0
(-6040 3560);
DISPLAY 0.659574 (-6040 3560);
PAINT MONO (-6040 3560);
DISPLAY INVISIBLE (-6040 3560);
FORCEPROP 1 LASTPIN (-6050 3550) BN 26
J 0
(-6062 3558);
DISPLAY 0.489362 (-6062 3558);
PAINT GREEN (-6062 3558);
FORCEPROP 2 LAST CDS_LIB mstr_standard
J 0
(-6000 3550);
DISPLAY 0.723404 (-6000 3550);
PAINT MONO (-6000 3550);
DISPLAY INVISIBLE (-6000 3550);
FORCEPROP 1 LAST BODY_TYPE PLUMBING
J 0
(-6000 3600);
DISPLAY 0.872340 (-6000 3600);
PAINT GREEN (-6000 3600);
DISPLAY INVISIBLE (-6000 3600);
FORCEPROP 1 LAST HDL_TAP TRUE
J 0
(-5675 3425);
DISPLAY 0.872340 (-5675 3425);
DISPLAY INVISIBLE (-5675 3425);
FORCEPROP 1 LAST PATH I62
J 0
(-6002 3550);
DISPLAY 0.872340 (-6002 3550);
PAINT GREEN (-6002 3550);
DISPLAY INVISIBLE (-6002 3550);
FORCEADD TAP..1
(-6000 3600);
FORCEPROP 3 LASTPIN (-6050 3600) SIG_NAME M_I_CPU0_SB_DQ<27>
J 0
(-6040 3610);
DISPLAY 0.659574 (-6040 3610);
PAINT MONO (-6040 3610);
DISPLAY INVISIBLE (-6040 3610);
FORCEPROP 1 LASTPIN (-6050 3600) BN 27
J 0
(-6062 3608);
DISPLAY 0.489362 (-6062 3608);
PAINT GREEN (-6062 3608);
FORCEPROP 2 LAST CDS_LIB mstr_standard
J 0
(-6000 3600);
DISPLAY 0.723404 (-6000 3600);
PAINT MONO (-6000 3600);
DISPLAY INVISIBLE (-6000 3600);
FORCEPROP 1 LAST BODY_TYPE PLUMBING
J 0
(-6000 3650);
DISPLAY 0.872340 (-6000 3650);
PAINT GREEN (-6000 3650);
DISPLAY INVISIBLE (-6000 3650);
FORCEPROP 1 LAST HDL_TAP TRUE
J 0
(-5675 3475);
DISPLAY 0.872340 (-5675 3475);
DISPLAY INVISIBLE (-5675 3475);
FORCEPROP 1 LAST PATH I63
J 0
(-6002 3600);
DISPLAY 0.872340 (-6002 3600);
PAINT GREEN (-6002 3600);
DISPLAY INVISIBLE (-6002 3600);
FORCEADD TAP..1
(-6000 3650);
FORCEPROP 3 LASTPIN (-6050 3650) SIG_NAME M_I_CPU0_SB_DQ<28>
J 0
(-6040 3660);
DISPLAY 0.659574 (-6040 3660);
PAINT MONO (-6040 3660);
DISPLAY INVISIBLE (-6040 3660);
FORCEPROP 1 LASTPIN (-6050 3650) BN 28
J 0
(-6062 3658);
DISPLAY 0.489362 (-6062 3658);
PAINT GREEN (-6062 3658);
FORCEPROP 2 LAST CDS_LIB mstr_standard
J 0
(-6000 3650);
DISPLAY 0.723404 (-6000 3650);
PAINT MONO (-6000 3650);
DISPLAY INVISIBLE (-6000 3650);
FORCEPROP 1 LAST BODY_TYPE PLUMBING
J 0
(-6000 3700);
DISPLAY 0.872340 (-6000 3700);
PAINT GREEN (-6000 3700);
DISPLAY INVISIBLE (-6000 3700);
FORCEPROP 1 LAST HDL_TAP TRUE
J 0
(-5675 3525);
DISPLAY 0.872340 (-5675 3525);
DISPLAY INVISIBLE (-5675 3525);
FORCEPROP 1 LAST PATH I64
J 0
(-6002 3650);
DISPLAY 0.872340 (-6002 3650);
PAINT GREEN (-6002 3650);
DISPLAY INVISIBLE (-6002 3650);
FORCEADD TAP..1
(-6000 3700);
FORCEPROP 3 LASTPIN (-6050 3700) SIG_NAME M_I_CPU0_SB_DQ<29>
J 0
(-6040 3710);
DISPLAY 0.659574 (-6040 3710);
PAINT MONO (-6040 3710);
DISPLAY INVISIBLE (-6040 3710);
FORCEPROP 1 LASTPIN (-6050 3700) BN 29
J 0
(-6062 3708);
DISPLAY 0.489362 (-6062 3708);
PAINT GREEN (-6062 3708);
FORCEPROP 2 LAST CDS_LIB mstr_standard
J 0
(-6000 3700);
DISPLAY 0.723404 (-6000 3700);
PAINT MONO (-6000 3700);
DISPLAY INVISIBLE (-6000 3700);
FORCEPROP 1 LAST BODY_TYPE PLUMBING
J 0
(-6000 3750);
DISPLAY 0.872340 (-6000 3750);
PAINT GREEN (-6000 3750);
DISPLAY INVISIBLE (-6000 3750);
FORCEPROP 1 LAST HDL_TAP TRUE
J 0
(-5675 3575);
DISPLAY 0.872340 (-5675 3575);
DISPLAY INVISIBLE (-5675 3575);
FORCEPROP 1 LAST PATH I65
J 0
(-6002 3700);
DISPLAY 0.872340 (-6002 3700);
PAINT GREEN (-6002 3700);
DISPLAY INVISIBLE (-6002 3700);
FORCEADD TAP..1
(-6000 3800);
FORCEPROP 3 LASTPIN (-6050 3800) SIG_NAME M_I_CPU0_SB_DQ<31>
J 0
(-6040 3810);
DISPLAY 0.659574 (-6040 3810);
PAINT MONO (-6040 3810);
DISPLAY INVISIBLE (-6040 3810);
FORCEPROP 1 LASTPIN (-6050 3800) BN 31
J 0
(-6062 3808);
DISPLAY 0.489362 (-6062 3808);
PAINT GREEN (-6062 3808);
FORCEPROP 2 LAST CDS_LIB mstr_standard
J 0
(-6000 3800);
DISPLAY 0.723404 (-6000 3800);
PAINT MONO (-6000 3800);
DISPLAY INVISIBLE (-6000 3800);
FORCEPROP 1 LAST BODY_TYPE PLUMBING
J 0
(-6000 3850);
DISPLAY 0.872340 (-6000 3850);
PAINT GREEN (-6000 3850);
DISPLAY INVISIBLE (-6000 3850);
FORCEPROP 1 LAST HDL_TAP TRUE
J 0
(-5675 3675);
DISPLAY 0.872340 (-5675 3675);
DISPLAY INVISIBLE (-5675 3675);
FORCEPROP 1 LAST PATH I66
J 0
(-6002 3800);
DISPLAY 0.872340 (-6002 3800);
PAINT GREEN (-6002 3800);
DISPLAY INVISIBLE (-6002 3800);
FORCEADD TAP..1
(-6000 3750);
FORCEPROP 3 LASTPIN (-6050 3750) SIG_NAME M_I_CPU0_SB_DQ<30>
J 0
(-6040 3760);
DISPLAY 0.659574 (-6040 3760);
PAINT MONO (-6040 3760);
DISPLAY INVISIBLE (-6040 3760);
FORCEPROP 1 LASTPIN (-6050 3750) BN 30
J 0
(-6062 3758);
DISPLAY 0.489362 (-6062 3758);
PAINT GREEN (-6062 3758);
FORCEPROP 2 LAST CDS_LIB mstr_standard
J 0
(-6000 3750);
DISPLAY 0.723404 (-6000 3750);
PAINT MONO (-6000 3750);
DISPLAY INVISIBLE (-6000 3750);
FORCEPROP 1 LAST BODY_TYPE PLUMBING
J 0
(-6000 3800);
DISPLAY 0.872340 (-6000 3800);
PAINT GREEN (-6000 3800);
DISPLAY INVISIBLE (-6000 3800);
FORCEPROP 1 LAST HDL_TAP TRUE
J 0
(-5675 3625);
DISPLAY 0.872340 (-5675 3625);
DISPLAY INVISIBLE (-5675 3625);
FORCEPROP 1 LAST PATH I67
J 0
(-6002 3750);
DISPLAY 0.872340 (-6002 3750);
PAINT GREEN (-6002 3750);
DISPLAY INVISIBLE (-6002 3750);
FORCEADD TAP..1
(-6000 3900);
FORCEPROP 3 LASTPIN (-6050 3900) SIG_NAME M_I_CPU0_SA_DQ<0>
J 0
(-6040 3910);
DISPLAY 0.659574 (-6040 3910);
PAINT MONO (-6040 3910);
DISPLAY INVISIBLE (-6040 3910);
FORCEPROP 1 LASTPIN (-6050 3900) BN 0
J 0
(-6062 3908);
DISPLAY 0.489362 (-6062 3908);
PAINT GREEN (-6062 3908);
FORCEPROP 2 LAST CDS_LIB mstr_standard
J 0
(-6000 3900);
DISPLAY 0.723404 (-6000 3900);
PAINT MONO (-6000 3900);
DISPLAY INVISIBLE (-6000 3900);
FORCEPROP 1 LAST BODY_TYPE PLUMBING
J 0
(-6000 3950);
DISPLAY 0.872340 (-6000 3950);
PAINT GREEN (-6000 3950);
DISPLAY INVISIBLE (-6000 3950);
FORCEPROP 1 LAST HDL_TAP TRUE
J 0
(-5675 3775);
DISPLAY 0.872340 (-5675 3775);
DISPLAY INVISIBLE (-5675 3775);
FORCEPROP 1 LAST PATH I68
J 0
(-6002 3900);
DISPLAY 0.872340 (-6002 3900);
PAINT GREEN (-6002 3900);
DISPLAY INVISIBLE (-6002 3900);
FORCEADD OFFPAGE..5
(-8125 3100);
FORCEPROP 2 LAST $XR0 18 
J 0
(-8349 3100);
DISPLAY 0.638298 (-8349 3100);
PAINT MONO (-8349 3100);
FORCEPROP 2 LAST CDS_LIB mstr_standard
J 0
(-8125 3100);
DISPLAY INVISIBLE (-8125 3100);
FORCEPROP 1 LAST OFFPAGE TRUE
J 0
(-7800 2975);
DISPLAY 0.872340 (-7800 2975);
PAINT GREEN (-7800 2975);
DISPLAY INVISIBLE (-7800 2975);
FORCEPROP 1 LAST COMMENT_BODY TRUE
J 0
(-8025 3025);
DISPLAY 0.872340 (-8025 3025);
PAINT GREEN (-8025 3025);
DISPLAY INVISIBLE (-8025 3025);
FORCEPROP 2 LAST PATH I7
J 0
(-8075 3175);
DISPLAY 1.021277 (-8075 3175);
DISPLAY INVISIBLE (-8075 3175);
FORCEADD OFFPAGE..3
(-5325 3825);
FORCEPROP 2 LAST $XR0 18 
J 0
(-5111 3825);
DISPLAY 0.638298 (-5111 3825);
PAINT MONO (-5111 3825);
FORCEPROP 2 LAST CDS_LIB mstr_standard
J 0
(-5325 3825);
DISPLAY 0.723404 (-5325 3825);
PAINT MONO (-5325 3825);
DISPLAY INVISIBLE (-5325 3825);
FORCEPROP 1 LAST OFFPAGE TRUE
J 0
(-5000 3700);
DISPLAY 0.872340 (-5000 3700);
PAINT GREEN (-5000 3700);
DISPLAY INVISIBLE (-5000 3700);
FORCEPROP 1 LAST COMMENT_BODY TRUE
J 0
(-5375 3725);
DISPLAY 0.872340 (-5375 3725);
PAINT GREEN (-5375 3725);
DISPLAY INVISIBLE (-5375 3725);
FORCEPROP 2 LAST PATH I76
J 0
(-5125 3900);
DISPLAY 1.021277 (-5125 3900);
DISPLAY INVISIBLE (-5125 3900);
FORCEADD TAP..1
R 2
(-7700 4050);
FORCEPROP 3 LASTPIN (-7650 4050) SIG_NAME M_I_CPU0_SA_CB<7>
J 0
(-7640 4060);
DISPLAY 0.659574 (-7640 4060);
PAINT MONO (-7640 4060);
DISPLAY INVISIBLE (-7640 4060);
FORCEPROP 1 LASTPIN (-7650 4050) BN 7
J 2
(-7638 4058);
DISPLAY 0.489362 (-7638 4058);
PAINT GREEN (-7638 4058);
FORCEPROP 2 LAST CDS_LIB mstr_standard
J 0
(-7700 4050);
DISPLAY 0.723404 (-7700 4050);
PAINT MONO (-7700 4050);
DISPLAY INVISIBLE (-7700 4050);
FORCEPROP 1 LAST BODY_TYPE PLUMBING
J 2
(-7700 4100);
DISPLAY 0.872340 (-7700 4100);
PAINT GREEN (-7700 4100);
DISPLAY INVISIBLE (-7700 4100);
FORCEPROP 1 LAST HDL_TAP TRUE
J 2
(-8025 3925);
DISPLAY 0.872340 (-8025 3925);
DISPLAY INVISIBLE (-8025 3925);
FORCEPROP 1 LAST PATH I77
J 2
(-7698 4050);
DISPLAY 0.872340 (-7698 4050);
PAINT GREEN (-7698 4050);
DISPLAY INVISIBLE (-7698 4050);
FORCEADD TAP..1
R 2
(-7700 4000);
FORCEPROP 3 LASTPIN (-7650 4000) SIG_NAME M_I_CPU0_SA_CB<6>
J 0
(-7640 4010);
DISPLAY 0.659574 (-7640 4010);
PAINT MONO (-7640 4010);
DISPLAY INVISIBLE (-7640 4010);
FORCEPROP 1 LASTPIN (-7650 4000) BN 6
J 2
(-7638 4008);
DISPLAY 0.489362 (-7638 4008);
PAINT GREEN (-7638 4008);
FORCEPROP 2 LAST CDS_LIB mstr_standard
J 0
(-7700 4000);
DISPLAY 0.723404 (-7700 4000);
PAINT MONO (-7700 4000);
DISPLAY INVISIBLE (-7700 4000);
FORCEPROP 1 LAST BODY_TYPE PLUMBING
J 2
(-7700 4050);
DISPLAY 0.872340 (-7700 4050);
PAINT GREEN (-7700 4050);
DISPLAY INVISIBLE (-7700 4050);
FORCEPROP 1 LAST HDL_TAP TRUE
J 2
(-8025 3875);
DISPLAY 0.872340 (-8025 3875);
DISPLAY INVISIBLE (-8025 3875);
FORCEPROP 1 LAST PATH I78
J 2
(-7698 4000);
DISPLAY 0.872340 (-7698 4000);
PAINT GREEN (-7698 4000);
DISPLAY INVISIBLE (-7698 4000);
FORCEADD TAP..1
R 2
(-7700 3950);
FORCEPROP 3 LASTPIN (-7650 3950) SIG_NAME M_I_CPU0_SA_CB<5>
J 0
(-7640 3960);
DISPLAY 0.659574 (-7640 3960);
PAINT MONO (-7640 3960);
DISPLAY INVISIBLE (-7640 3960);
FORCEPROP 1 LASTPIN (-7650 3950) BN 5
J 2
(-7638 3958);
DISPLAY 0.489362 (-7638 3958);
PAINT GREEN (-7638 3958);
FORCEPROP 2 LAST CDS_LIB mstr_standard
J 0
(-7700 3950);
DISPLAY 0.723404 (-7700 3950);
PAINT MONO (-7700 3950);
DISPLAY INVISIBLE (-7700 3950);
FORCEPROP 1 LAST BODY_TYPE PLUMBING
J 2
(-7700 4000);
DISPLAY 0.872340 (-7700 4000);
PAINT GREEN (-7700 4000);
DISPLAY INVISIBLE (-7700 4000);
FORCEPROP 1 LAST HDL_TAP TRUE
J 2
(-8025 3825);
DISPLAY 0.872340 (-8025 3825);
DISPLAY INVISIBLE (-8025 3825);
FORCEPROP 1 LAST PATH I79
J 2
(-7698 3950);
DISPLAY 0.872340 (-7698 3950);
PAINT GREEN (-7698 3950);
DISPLAY INVISIBLE (-7698 3950);
FORCEADD OFFPAGE..1
(-8125 3150);
FORCEPROP 2 LAST $XR0 18 
J 0
(-8376 3150);
DISPLAY 0.638298 (-8376 3150);
PAINT MONO (-8376 3150);
FORCEPROP 2 LAST CDS_LIB mstr_standard
J 0
(-8125 3150);
DISPLAY 0.808511 (-8125 3150);
DISPLAY INVISIBLE (-8125 3150);
FORCEPROP 1 LAST OFFPAGE TRUE
J 0
(-7800 3025);
DISPLAY 0.872340 (-7800 3025);
PAINT GREEN (-7800 3025);
DISPLAY INVISIBLE (-7800 3025);
FORCEPROP 1 LAST COMMENT_BODY TRUE
J 0
(-8000 3050);
DISPLAY 0.872340 (-8000 3050);
PAINT GREEN (-8000 3050);
DISPLAY INVISIBLE (-8000 3050);
FORCEPROP 2 LAST PATH I8
J 0
(-8550 3200);
DISPLAY 1.021277 (-8550 3200);
DISPLAY INVISIBLE (-8550 3200);
FORCEADD TAP..1
R 2
(-7700 4900);
FORCEPROP 3 LASTPIN (-7650 4900) SIG_NAME M_I_CPU0_SB_CA<3>
J 0
(-7640 4910);
DISPLAY 0.659574 (-7640 4910);
PAINT MONO (-7640 4910);
DISPLAY INVISIBLE (-7640 4910);
FORCEPROP 1 LASTPIN (-7650 4900) BN 3
J 2
(-7638 4908);
DISPLAY 0.489362 (-7638 4908);
PAINT GREEN (-7638 4908);
FORCEPROP 2 LAST CDS_LIB mstr_standard
J 0
(-7700 4900);
DISPLAY 0.723404 (-7700 4900);
PAINT MONO (-7700 4900);
DISPLAY INVISIBLE (-7700 4900);
FORCEPROP 1 LAST BODY_TYPE PLUMBING
J 2
(-7700 4950);
DISPLAY 0.872340 (-7700 4950);
PAINT GREEN (-7700 4950);
DISPLAY INVISIBLE (-7700 4950);
FORCEPROP 1 LAST HDL_TAP TRUE
J 2
(-8025 4775);
DISPLAY 0.872340 (-8025 4775);
DISPLAY INVISIBLE (-8025 4775);
FORCEPROP 1 LAST PATH I80
J 2
(-7698 4900);
DISPLAY 0.872340 (-7698 4900);
PAINT GREEN (-7698 4900);
DISPLAY INVISIBLE (-7698 4900);
FORCEADD TAP..1
R 2
(-7700 4850);
FORCEPROP 3 LASTPIN (-7650 4850) SIG_NAME M_I_CPU0_SB_CA<2>
J 0
(-7640 4860);
DISPLAY 0.659574 (-7640 4860);
PAINT MONO (-7640 4860);
DISPLAY INVISIBLE (-7640 4860);
FORCEPROP 1 LASTPIN (-7650 4850) BN 2
J 2
(-7638 4858);
DISPLAY 0.489362 (-7638 4858);
PAINT GREEN (-7638 4858);
FORCEPROP 2 LAST CDS_LIB mstr_standard
J 0
(-7700 4850);
DISPLAY 0.723404 (-7700 4850);
PAINT MONO (-7700 4850);
DISPLAY INVISIBLE (-7700 4850);
FORCEPROP 1 LAST BODY_TYPE PLUMBING
J 2
(-7700 4900);
DISPLAY 0.872340 (-7700 4900);
PAINT GREEN (-7700 4900);
DISPLAY INVISIBLE (-7700 4900);
FORCEPROP 1 LAST HDL_TAP TRUE
J 2
(-8025 4725);
DISPLAY 0.872340 (-8025 4725);
DISPLAY INVISIBLE (-8025 4725);
FORCEPROP 1 LAST PATH I81
J 2
(-7698 4850);
DISPLAY 0.872340 (-7698 4850);
PAINT GREEN (-7698 4850);
DISPLAY INVISIBLE (-7698 4850);
FORCEADD TAP..1
R 2
(-7700 4800);
FORCEPROP 3 LASTPIN (-7650 4800) SIG_NAME M_I_CPU0_SB_CA<1>
J 0
(-7640 4810);
DISPLAY 0.659574 (-7640 4810);
PAINT MONO (-7640 4810);
DISPLAY INVISIBLE (-7640 4810);
FORCEPROP 1 LASTPIN (-7650 4800) BN 1
J 2
(-7638 4808);
DISPLAY 0.489362 (-7638 4808);
PAINT GREEN (-7638 4808);
FORCEPROP 2 LAST CDS_LIB mstr_standard
J 0
(-7700 4800);
DISPLAY 0.723404 (-7700 4800);
PAINT MONO (-7700 4800);
DISPLAY INVISIBLE (-7700 4800);
FORCEPROP 1 LAST BODY_TYPE PLUMBING
J 2
(-7700 4850);
DISPLAY 0.872340 (-7700 4850);
PAINT GREEN (-7700 4850);
DISPLAY INVISIBLE (-7700 4850);
FORCEPROP 1 LAST HDL_TAP TRUE
J 2
(-8025 4675);
DISPLAY 0.872340 (-8025 4675);
DISPLAY INVISIBLE (-8025 4675);
FORCEPROP 1 LAST PATH I82
J 2
(-7698 4800);
DISPLAY 0.872340 (-7698 4800);
PAINT GREEN (-7698 4800);
DISPLAY INVISIBLE (-7698 4800);
FORCEADD TAP..1
R 2
(-7700 4750);
FORCEPROP 3 LASTPIN (-7650 4750) SIG_NAME M_I_CPU0_SB_CA<0>
J 0
(-7640 4760);
DISPLAY 0.659574 (-7640 4760);
PAINT MONO (-7640 4760);
DISPLAY INVISIBLE (-7640 4760);
FORCEPROP 1 LASTPIN (-7650 4750) BN 0
J 2
(-7638 4758);
DISPLAY 0.489362 (-7638 4758);
PAINT GREEN (-7638 4758);
FORCEPROP 2 LAST CDS_LIB mstr_standard
J 0
(-7700 4750);
DISPLAY 0.723404 (-7700 4750);
PAINT MONO (-7700 4750);
DISPLAY INVISIBLE (-7700 4750);
FORCEPROP 1 LAST BODY_TYPE PLUMBING
J 2
(-7700 4800);
DISPLAY 0.872340 (-7700 4800);
PAINT GREEN (-7700 4800);
DISPLAY INVISIBLE (-7700 4800);
FORCEPROP 1 LAST HDL_TAP TRUE
J 2
(-8025 4625);
DISPLAY 0.872340 (-8025 4625);
DISPLAY INVISIBLE (-8025 4625);
FORCEPROP 1 LAST PATH I83
J 2
(-7698 4750);
DISPLAY 0.872340 (-7698 4750);
PAINT GREEN (-7698 4750);
DISPLAY INVISIBLE (-7698 4750);
FORCEADD TAP..1
R 2
(-7700 4950);
FORCEPROP 3 LASTPIN (-7650 4950) SIG_NAME M_I_CPU0_SB_CA<4>
J 0
(-7640 4960);
DISPLAY 0.659574 (-7640 4960);
PAINT MONO (-7640 4960);
DISPLAY INVISIBLE (-7640 4960);
FORCEPROP 1 LASTPIN (-7650 4950) BN 4
J 2
(-7638 4958);
DISPLAY 0.489362 (-7638 4958);
PAINT GREEN (-7638 4958);
FORCEPROP 2 LAST CDS_LIB mstr_standard
J 0
(-7700 4950);
DISPLAY 0.723404 (-7700 4950);
PAINT MONO (-7700 4950);
DISPLAY INVISIBLE (-7700 4950);
FORCEPROP 1 LAST BODY_TYPE PLUMBING
J 2
(-7700 5000);
DISPLAY 0.872340 (-7700 5000);
PAINT GREEN (-7700 5000);
DISPLAY INVISIBLE (-7700 5000);
FORCEPROP 1 LAST HDL_TAP TRUE
J 2
(-8025 4825);
DISPLAY 0.872340 (-8025 4825);
DISPLAY INVISIBLE (-8025 4825);
FORCEPROP 1 LAST PATH I84
J 2
(-7698 4950);
DISPLAY 0.872340 (-7698 4950);
PAINT GREEN (-7698 4950);
DISPLAY INVISIBLE (-7698 4950);
FORCEADD TAP..1
R 2
(-7700 5000);
FORCEPROP 3 LASTPIN (-7650 5000) SIG_NAME M_I_CPU0_SB_CA<5>
J 0
(-7640 5010);
DISPLAY 0.659574 (-7640 5010);
PAINT MONO (-7640 5010);
DISPLAY INVISIBLE (-7640 5010);
FORCEPROP 1 LASTPIN (-7650 5000) BN 5
J 2
(-7638 5008);
DISPLAY 0.489362 (-7638 5008);
PAINT GREEN (-7638 5008);
FORCEPROP 2 LAST CDS_LIB mstr_standard
J 0
(-7700 5000);
DISPLAY 0.723404 (-7700 5000);
PAINT MONO (-7700 5000);
DISPLAY INVISIBLE (-7700 5000);
FORCEPROP 1 LAST BODY_TYPE PLUMBING
J 2
(-7700 5050);
DISPLAY 0.872340 (-7700 5050);
PAINT GREEN (-7700 5050);
DISPLAY INVISIBLE (-7700 5050);
FORCEPROP 1 LAST HDL_TAP TRUE
J 2
(-8025 4875);
DISPLAY 0.872340 (-8025 4875);
DISPLAY INVISIBLE (-8025 4875);
FORCEPROP 1 LAST PATH I85
J 2
(-7698 5000);
DISPLAY 0.872340 (-7698 5000);
PAINT GREEN (-7698 5000);
DISPLAY INVISIBLE (-7698 5000);
FORCEADD TAP..1
R 2
(-7700 5050);
FORCEPROP 3 LASTPIN (-7650 5050) SIG_NAME M_I_CPU0_SB_CA<6>
J 0
(-7640 5060);
DISPLAY 0.659574 (-7640 5060);
PAINT MONO (-7640 5060);
DISPLAY INVISIBLE (-7640 5060);
FORCEPROP 1 LASTPIN (-7650 5050) BN 6
J 2
(-7638 5058);
DISPLAY 0.489362 (-7638 5058);
PAINT GREEN (-7638 5058);
FORCEPROP 2 LAST CDS_LIB mstr_standard
J 0
(-7700 5050);
DISPLAY 0.723404 (-7700 5050);
PAINT MONO (-7700 5050);
DISPLAY INVISIBLE (-7700 5050);
FORCEPROP 1 LAST BODY_TYPE PLUMBING
J 2
(-7700 5100);
DISPLAY 0.872340 (-7700 5100);
PAINT GREEN (-7700 5100);
DISPLAY INVISIBLE (-7700 5100);
FORCEPROP 1 LAST HDL_TAP TRUE
J 2
(-8025 4925);
DISPLAY 0.872340 (-8025 4925);
DISPLAY INVISIBLE (-8025 4925);
FORCEPROP 1 LAST PATH I86
J 2
(-7698 5050);
DISPLAY 0.872340 (-7698 5050);
PAINT GREEN (-7698 5050);
DISPLAY INVISIBLE (-7698 5050);
FORCEADD TAP..1
R 2
(-7700 5200);
FORCEPROP 3 LASTPIN (-7650 5200) SIG_NAME M_I_CPU0_SA_CA<1>
J 0
(-7640 5210);
DISPLAY 0.659574 (-7640 5210);
PAINT MONO (-7640 5210);
DISPLAY INVISIBLE (-7640 5210);
FORCEPROP 1 LASTPIN (-7650 5200) BN 1
J 2
(-7638 5208);
DISPLAY 0.489362 (-7638 5208);
PAINT GREEN (-7638 5208);
FORCEPROP 2 LAST CDS_LIB mstr_standard
J 0
(-7700 5200);
DISPLAY 0.723404 (-7700 5200);
PAINT MONO (-7700 5200);
DISPLAY INVISIBLE (-7700 5200);
FORCEPROP 1 LAST BODY_TYPE PLUMBING
J 2
(-7700 5250);
DISPLAY 0.872340 (-7700 5250);
PAINT GREEN (-7700 5250);
DISPLAY INVISIBLE (-7700 5250);
FORCEPROP 1 LAST HDL_TAP TRUE
J 2
(-8025 5075);
DISPLAY 0.872340 (-8025 5075);
DISPLAY INVISIBLE (-8025 5075);
FORCEPROP 1 LAST PATH I87
J 2
(-7698 5200);
DISPLAY 0.872340 (-7698 5200);
PAINT GREEN (-7698 5200);
DISPLAY INVISIBLE (-7698 5200);
FORCEADD TAP..1
R 2
(-7700 5150);
FORCEPROP 3 LASTPIN (-7650 5150) SIG_NAME M_I_CPU0_SA_CA<0>
J 0
(-7640 5160);
DISPLAY 0.659574 (-7640 5160);
PAINT MONO (-7640 5160);
DISPLAY INVISIBLE (-7640 5160);
FORCEPROP 1 LASTPIN (-7650 5150) BN 0
J 2
(-7638 5158);
DISPLAY 0.489362 (-7638 5158);
PAINT GREEN (-7638 5158);
FORCEPROP 2 LAST CDS_LIB mstr_standard
J 0
(-7700 5150);
DISPLAY 0.723404 (-7700 5150);
PAINT MONO (-7700 5150);
DISPLAY INVISIBLE (-7700 5150);
FORCEPROP 1 LAST BODY_TYPE PLUMBING
J 2
(-7700 5200);
DISPLAY 0.872340 (-7700 5200);
PAINT GREEN (-7700 5200);
DISPLAY INVISIBLE (-7700 5200);
FORCEPROP 1 LAST HDL_TAP TRUE
J 2
(-8025 5025);
DISPLAY 0.872340 (-8025 5025);
DISPLAY INVISIBLE (-8025 5025);
FORCEPROP 1 LAST PATH I88
J 2
(-7698 5150);
DISPLAY 0.872340 (-7698 5150);
PAINT GREEN (-7698 5150);
DISPLAY INVISIBLE (-7698 5150);
FORCEADD TAP..1
R 2
(-7700 5250);
FORCEPROP 3 LASTPIN (-7650 5250) SIG_NAME M_I_CPU0_SA_CA<2>
J 0
(-7640 5260);
DISPLAY 0.659574 (-7640 5260);
PAINT MONO (-7640 5260);
DISPLAY INVISIBLE (-7640 5260);
FORCEPROP 1 LASTPIN (-7650 5250) BN 2
J 2
(-7638 5258);
DISPLAY 0.489362 (-7638 5258);
PAINT GREEN (-7638 5258);
FORCEPROP 2 LAST CDS_LIB mstr_standard
J 0
(-7700 5250);
DISPLAY 0.723404 (-7700 5250);
PAINT MONO (-7700 5250);
DISPLAY INVISIBLE (-7700 5250);
FORCEPROP 1 LAST BODY_TYPE PLUMBING
J 2
(-7700 5300);
DISPLAY 0.872340 (-7700 5300);
PAINT GREEN (-7700 5300);
DISPLAY INVISIBLE (-7700 5300);
FORCEPROP 1 LAST HDL_TAP TRUE
J 2
(-8025 5125);
DISPLAY 0.872340 (-8025 5125);
DISPLAY INVISIBLE (-8025 5125);
FORCEPROP 1 LAST PATH I89
J 2
(-7698 5250);
DISPLAY 0.872340 (-7698 5250);
PAINT GREEN (-7698 5250);
DISPLAY INVISIBLE (-7698 5250);
FORCEADD VCC_CORE..1
(-8550 3475);
FORCEPROP 3 LASTPIN (-8550 3425) SIG_NAME P3V3_AUX\g
J 0
(-8540 3435);
DISPLAY 0.659574 (-8540 3435);
PAINT MONO (-8540 3435);
DISPLAY INVISIBLE (-8540 3435);
FORCEPROP 1 LAST HDL_POWER P3V3_AUX
J 1
(-8550 3525);
DISPLAY 0.489362 (-8550 3525);
PAINT GREEN (-8550 3525);
FORCEPROP 2 LAST ROOM PVCCINFAON_CPU0_CTRL
J 0
(-8550 3575);
DISPLAY 0.808511 (-8550 3575);
PAINT RED (-8550 3575);
DISPLAY INVISIBLE (-8550 3575);
FORCEPROP 0 LAST VOLTAGE 3.3
J 0
(-8825 3625);
DISPLAY 1.021277 (-8825 3625);
PAINT SKYBLUE (-8825 3625);
DISPLAY INVISIBLE (-8825 3625);
FORCEPROP 2 LAST CDS_LIB mstr_symbols
J 0
(-8550 3475);
PAINT MONO (-8550 3475);
DISPLAY INVISIBLE (-8550 3475);
FORCEPROP 1 LAST PATH I9
J 0
(-8500 3500);
DISPLAY 0.872340 (-8500 3500);
PAINT AQUA (-8500 3500);
DISPLAY INVISIBLE (-8500 3500);
FORCEADD TAP..1
R 2
(-7700 5300);
FORCEPROP 3 LASTPIN (-7650 5300) SIG_NAME M_I_CPU0_SA_CA<3>
J 0
(-7640 5310);
DISPLAY 0.659574 (-7640 5310);
PAINT MONO (-7640 5310);
DISPLAY INVISIBLE (-7640 5310);
FORCEPROP 1 LASTPIN (-7650 5300) BN 3
J 2
(-7638 5308);
DISPLAY 0.489362 (-7638 5308);
PAINT GREEN (-7638 5308);
FORCEPROP 2 LAST CDS_LIB mstr_standard
J 0
(-7700 5300);
DISPLAY 0.723404 (-7700 5300);
PAINT MONO (-7700 5300);
DISPLAY INVISIBLE (-7700 5300);
FORCEPROP 1 LAST BODY_TYPE PLUMBING
J 2
(-7700 5350);
DISPLAY 0.872340 (-7700 5350);
PAINT GREEN (-7700 5350);
DISPLAY INVISIBLE (-7700 5350);
FORCEPROP 1 LAST HDL_TAP TRUE
J 2
(-8025 5175);
DISPLAY 0.872340 (-8025 5175);
DISPLAY INVISIBLE (-8025 5175);
FORCEPROP 1 LAST PATH I90
J 2
(-7698 5300);
DISPLAY 0.872340 (-7698 5300);
PAINT GREEN (-7698 5300);
DISPLAY INVISIBLE (-7698 5300);
FORCEADD TAP..1
R 2
(-7700 5350);
FORCEPROP 3 LASTPIN (-7650 5350) SIG_NAME M_I_CPU0_SA_CA<4>
J 0
(-7640 5360);
DISPLAY 0.659574 (-7640 5360);
PAINT MONO (-7640 5360);
DISPLAY INVISIBLE (-7640 5360);
FORCEPROP 1 LASTPIN (-7650 5350) BN 4
J 2
(-7638 5358);
DISPLAY 0.489362 (-7638 5358);
PAINT GREEN (-7638 5358);
FORCEPROP 2 LAST CDS_LIB mstr_standard
J 0
(-7700 5350);
DISPLAY 0.723404 (-7700 5350);
PAINT MONO (-7700 5350);
DISPLAY INVISIBLE (-7700 5350);
FORCEPROP 1 LAST BODY_TYPE PLUMBING
J 2
(-7700 5400);
DISPLAY 0.872340 (-7700 5400);
PAINT GREEN (-7700 5400);
DISPLAY INVISIBLE (-7700 5400);
FORCEPROP 1 LAST HDL_TAP TRUE
J 2
(-8025 5225);
DISPLAY 0.872340 (-8025 5225);
DISPLAY INVISIBLE (-8025 5225);
FORCEPROP 1 LAST PATH I91
J 2
(-7698 5350);
DISPLAY 0.872340 (-7698 5350);
PAINT GREEN (-7698 5350);
DISPLAY INVISIBLE (-7698 5350);
FORCEADD TAP..1
R 2
(-7700 5450);
FORCEPROP 3 LASTPIN (-7650 5450) SIG_NAME M_I_CPU0_SA_CA<6>
J 0
(-7640 5460);
DISPLAY 0.659574 (-7640 5460);
PAINT MONO (-7640 5460);
DISPLAY INVISIBLE (-7640 5460);
FORCEPROP 1 LASTPIN (-7650 5450) BN 6
J 2
(-7638 5458);
DISPLAY 0.489362 (-7638 5458);
PAINT GREEN (-7638 5458);
FORCEPROP 2 LAST CDS_LIB mstr_standard
J 0
(-7700 5450);
DISPLAY 0.723404 (-7700 5450);
PAINT MONO (-7700 5450);
DISPLAY INVISIBLE (-7700 5450);
FORCEPROP 1 LAST BODY_TYPE PLUMBING
J 2
(-7700 5500);
DISPLAY 0.872340 (-7700 5500);
PAINT GREEN (-7700 5500);
DISPLAY INVISIBLE (-7700 5500);
FORCEPROP 1 LAST HDL_TAP TRUE
J 2
(-8025 5325);
DISPLAY 0.872340 (-8025 5325);
DISPLAY INVISIBLE (-8025 5325);
FORCEPROP 1 LAST PATH I92
J 2
(-7698 5450);
DISPLAY 0.872340 (-7698 5450);
PAINT GREEN (-7698 5450);
DISPLAY INVISIBLE (-7698 5450);
FORCEADD TAP..1
R 2
(-7700 5400);
FORCEPROP 3 LASTPIN (-7650 5400) SIG_NAME M_I_CPU0_SA_CA<5>
J 0
(-7640 5410);
DISPLAY 0.659574 (-7640 5410);
PAINT MONO (-7640 5410);
DISPLAY INVISIBLE (-7640 5410);
FORCEPROP 1 LASTPIN (-7650 5400) BN 5
J 2
(-7638 5408);
DISPLAY 0.489362 (-7638 5408);
PAINT GREEN (-7638 5408);
FORCEPROP 2 LAST CDS_LIB mstr_standard
J 0
(-7700 5400);
DISPLAY 0.723404 (-7700 5400);
PAINT MONO (-7700 5400);
DISPLAY INVISIBLE (-7700 5400);
FORCEPROP 1 LAST BODY_TYPE PLUMBING
J 2
(-7700 5450);
DISPLAY 0.872340 (-7700 5450);
PAINT GREEN (-7700 5450);
DISPLAY INVISIBLE (-7700 5450);
FORCEPROP 1 LAST HDL_TAP TRUE
J 2
(-8025 5275);
DISPLAY 0.872340 (-8025 5275);
DISPLAY INVISIBLE (-8025 5275);
FORCEPROP 1 LAST PATH I93
J 2
(-7698 5400);
DISPLAY 0.872340 (-7698 5400);
PAINT GREEN (-7698 5400);
DISPLAY INVISIBLE (-7698 5400);
FORCEADD TAP..1
(-6000 3950);
FORCEPROP 3 LASTPIN (-6050 3950) SIG_NAME M_I_CPU0_SA_DQ<1>
J 0
(-6040 3960);
DISPLAY 0.659574 (-6040 3960);
PAINT MONO (-6040 3960);
DISPLAY INVISIBLE (-6040 3960);
FORCEPROP 1 LASTPIN (-6050 3950) BN 1
J 0
(-6062 3958);
DISPLAY 0.489362 (-6062 3958);
PAINT GREEN (-6062 3958);
FORCEPROP 2 LAST CDS_LIB mstr_standard
J 0
(-6000 3950);
DISPLAY 0.723404 (-6000 3950);
PAINT MONO (-6000 3950);
DISPLAY INVISIBLE (-6000 3950);
FORCEPROP 1 LAST BODY_TYPE PLUMBING
J 0
(-6000 4000);
DISPLAY 0.872340 (-6000 4000);
PAINT GREEN (-6000 4000);
DISPLAY INVISIBLE (-6000 4000);
FORCEPROP 1 LAST HDL_TAP TRUE
J 0
(-5675 3825);
DISPLAY 0.872340 (-5675 3825);
DISPLAY INVISIBLE (-5675 3825);
FORCEPROP 1 LAST PATH I94
J 0
(-6002 3950);
DISPLAY 0.872340 (-6002 3950);
PAINT GREEN (-6002 3950);
DISPLAY INVISIBLE (-6002 3950);
FORCEADD TAP..1
(-6000 4000);
FORCEPROP 3 LASTPIN (-6050 4000) SIG_NAME M_I_CPU0_SA_DQ<2>
J 0
(-6040 4010);
DISPLAY 0.659574 (-6040 4010);
PAINT MONO (-6040 4010);
DISPLAY INVISIBLE (-6040 4010);
FORCEPROP 1 LASTPIN (-6050 4000) BN 2
J 0
(-6062 4008);
DISPLAY 0.489362 (-6062 4008);
PAINT GREEN (-6062 4008);
FORCEPROP 2 LAST CDS_LIB mstr_standard
J 0
(-6000 4000);
DISPLAY 0.723404 (-6000 4000);
PAINT MONO (-6000 4000);
DISPLAY INVISIBLE (-6000 4000);
FORCEPROP 1 LAST BODY_TYPE PLUMBING
J 0
(-6000 4050);
DISPLAY 0.872340 (-6000 4050);
PAINT GREEN (-6000 4050);
DISPLAY INVISIBLE (-6000 4050);
FORCEPROP 1 LAST HDL_TAP TRUE
J 0
(-5675 3875);
DISPLAY 0.872340 (-5675 3875);
DISPLAY INVISIBLE (-5675 3875);
FORCEPROP 1 LAST PATH I95
J 0
(-6002 4000);
DISPLAY 0.872340 (-6002 4000);
PAINT GREEN (-6002 4000);
DISPLAY INVISIBLE (-6002 4000);
FORCEADD TAP..1
(-6000 4050);
FORCEPROP 3 LASTPIN (-6050 4050) SIG_NAME M_I_CPU0_SA_DQ<3>
J 0
(-6040 4060);
DISPLAY 0.659574 (-6040 4060);
PAINT MONO (-6040 4060);
DISPLAY INVISIBLE (-6040 4060);
FORCEPROP 1 LASTPIN (-6050 4050) BN 3
J 0
(-6062 4058);
DISPLAY 0.489362 (-6062 4058);
PAINT GREEN (-6062 4058);
FORCEPROP 2 LAST CDS_LIB mstr_standard
J 0
(-6000 4050);
DISPLAY 0.723404 (-6000 4050);
PAINT MONO (-6000 4050);
DISPLAY INVISIBLE (-6000 4050);
FORCEPROP 1 LAST BODY_TYPE PLUMBING
J 0
(-6000 4100);
DISPLAY 0.872340 (-6000 4100);
PAINT GREEN (-6000 4100);
DISPLAY INVISIBLE (-6000 4100);
FORCEPROP 1 LAST HDL_TAP TRUE
J 0
(-5675 3925);
DISPLAY 0.872340 (-5675 3925);
DISPLAY INVISIBLE (-5675 3925);
FORCEPROP 1 LAST PATH I96
J 0
(-6002 4050);
DISPLAY 0.872340 (-6002 4050);
PAINT GREEN (-6002 4050);
DISPLAY INVISIBLE (-6002 4050);
FORCEADD TAP..1
(-6000 4200);
FORCEPROP 3 LASTPIN (-6050 4200) SIG_NAME M_I_CPU0_SA_DQ<6>
J 0
(-6040 4210);
DISPLAY 0.659574 (-6040 4210);
PAINT MONO (-6040 4210);
DISPLAY INVISIBLE (-6040 4210);
FORCEPROP 1 LASTPIN (-6050 4200) BN 6
J 0
(-6062 4208);
DISPLAY 0.489362 (-6062 4208);
PAINT GREEN (-6062 4208);
FORCEPROP 2 LAST CDS_LIB mstr_standard
J 0
(-6000 4200);
DISPLAY 0.723404 (-6000 4200);
PAINT MONO (-6000 4200);
DISPLAY INVISIBLE (-6000 4200);
FORCEPROP 1 LAST BODY_TYPE PLUMBING
J 0
(-6000 4250);
DISPLAY 0.872340 (-6000 4250);
PAINT GREEN (-6000 4250);
DISPLAY INVISIBLE (-6000 4250);
FORCEPROP 1 LAST HDL_TAP TRUE
J 0
(-5675 4075);
DISPLAY 0.872340 (-5675 4075);
DISPLAY INVISIBLE (-5675 4075);
FORCEPROP 1 LAST PATH I97
J 0
(-6002 4200);
DISPLAY 0.872340 (-6002 4200);
PAINT GREEN (-6002 4200);
DISPLAY INVISIBLE (-6002 4200);
FORCEADD TAP..1
(-6000 4100);
FORCEPROP 3 LASTPIN (-6050 4100) SIG_NAME M_I_CPU0_SA_DQ<4>
J 0
(-6040 4110);
DISPLAY 0.659574 (-6040 4110);
PAINT MONO (-6040 4110);
DISPLAY INVISIBLE (-6040 4110);
FORCEPROP 1 LASTPIN (-6050 4100) BN 4
J 0
(-6062 4108);
DISPLAY 0.489362 (-6062 4108);
PAINT GREEN (-6062 4108);
FORCEPROP 2 LAST CDS_LIB mstr_standard
J 0
(-6000 4100);
DISPLAY 0.723404 (-6000 4100);
PAINT MONO (-6000 4100);
DISPLAY INVISIBLE (-6000 4100);
FORCEPROP 1 LAST BODY_TYPE PLUMBING
J 0
(-6000 4150);
DISPLAY 0.872340 (-6000 4150);
PAINT GREEN (-6000 4150);
DISPLAY INVISIBLE (-6000 4150);
FORCEPROP 1 LAST HDL_TAP TRUE
J 0
(-5675 3975);
DISPLAY 0.872340 (-5675 3975);
DISPLAY INVISIBLE (-5675 3975);
FORCEPROP 1 LAST PATH I98
J 0
(-6002 4100);
DISPLAY 0.872340 (-6002 4100);
PAINT GREEN (-6002 4100);
DISPLAY INVISIBLE (-6002 4100);
FORCEADD TAP..1
(-6000 4150);
FORCEPROP 3 LASTPIN (-6050 4150) SIG_NAME M_I_CPU0_SA_DQ<5>
J 0
(-6040 4160);
DISPLAY 0.659574 (-6040 4160);
PAINT MONO (-6040 4160);
DISPLAY INVISIBLE (-6040 4160);
FORCEPROP 1 LASTPIN (-6050 4150) BN 5
J 0
(-6062 4158);
DISPLAY 0.489362 (-6062 4158);
PAINT GREEN (-6062 4158);
FORCEPROP 2 LAST CDS_LIB mstr_standard
J 0
(-6000 4150);
DISPLAY 0.723404 (-6000 4150);
PAINT MONO (-6000 4150);
DISPLAY INVISIBLE (-6000 4150);
FORCEPROP 1 LAST BODY_TYPE PLUMBING
J 0
(-6000 4200);
DISPLAY 0.872340 (-6000 4200);
PAINT GREEN (-6000 4200);
DISPLAY INVISIBLE (-6000 4200);
FORCEPROP 1 LAST HDL_TAP TRUE
J 0
(-5675 4025);
DISPLAY 0.872340 (-5675 4025);
DISPLAY INVISIBLE (-5675 4025);
FORCEPROP 1 LAST PATH I99
J 0
(-6002 4150);
DISPLAY 0.872340 (-6002 4150);
PAINT GREEN (-6002 4150);
DISPLAY INVISIBLE (-6002 4150);
FORCEADD DNS..2
(-8325 2350);
PAINT RED (-8325 2350);
FORCEPROP 2 LAST CDS_LIB mstr_misc
J 0
(-8325 2350);
DISPLAY INVISIBLE (-8325 2350);
FORCEPROP 1 LAST COMMENT_BODY TRUE
R 1
J 0
(-8250 2125);
DISPLAY 0.872340 (-8250 2125);
PAINT PEACH (-8250 2125);
DISPLAY INVISIBLE (-8250 2125);
FORCEADD QUANTA_TITLE_BLOCK_C..1
(0 0);
FORCEPROP 0 LAST CDS_CON_LAST_MODIFIED Thu Sep 14 16:12:08 2023
J 0
(-1885 15);
DISPLAY INVISIBLE (-1885 15);
FORCEPROP 1 LAST CUSTOM_TXT_CDS <CON_LAST_MODIFIED>
J 0
(-1885 15);
DISPLAY 0.978723 (-1885 15);
FORCEPROP 2 LAST CUSTOM_TXT_CDS <XR_PAGE_TITLE>
J 0
(-7890 5250);
DISPLAY 0.638298 (-7890 5250);
PAINT PINK (-7890 5250);
DISPLAY INVISIBLE (-7890 5250);
FORCEPROP 1 LAST CUSTOM_TXT_CDS <NAME_2>
J 0
(-3175 50);
FORCEPROP 1 LAST CUSTOM_TXT_CDS <NAME_1>
J 0
(-3175 175);
FORCEPROP 1 LAST CUSTOM_TXT_CDS <Q_NUMBER>
J 0
(-1403 103);
DISPLAY 1.212766 (-1403 103);
FORCEPROP 1 LAST CUSTOM_TXT_CDS <Q_PROJ>
J 0
(-2382 102);
DISPLAY 1.212766 (-2382 102);
FORCEPROP 1 LAST CUSTOM_TXT_CDS <Q_REV>
J 0
(-184 103);
DISPLAY 1.212766 (-184 103);
FORCEPROP 1 LAST CUSTOM_TXT_CDS <CON_PAGE_NUM> OF <CON_TOTAL_PAGES>
J 0
(-446 18);
DISPLAY 0.978723 (-446 18);
FORCEPROP 1 LAST Q_TITLE DDR5 - CPU0 CHI
J 0
(-9325 50);
DISPLAY 2.446809 (-9325 50);
PAINT GREEN (-9325 50);
FORCEPROP 2 LAST PAGE_BORDER TRUE
J 0
(-7890 5250);
DISPLAY 0.638298 (-7890 5250);
PAINT PINK (-7890 5250);
DISPLAY INVISIBLE (-7890 5250);
FORCEPROP 1 LAST CDS_LMAN_SYM_OUTLINE -9475,6775,100,-125
J 0
(0 0);
DISPLAY 0.468085 (0 0);
PAINT GREEN (0 0);
DISPLAY INVISIBLE (0 0);
FORCEPROP 2 LAST CDS_LIB pure_quanta
J 0
(0 0);
DISPLAY INVISIBLE (0 0);
FORCEPROP 2 LAST CDS_XR_PAGE_TITLE CR-94 : @T6G_MB_LIB.T6G(SCH_1):PAGE94
J 0
(-7890 5250);
DISPLAY 0.638298 (-7890 5250);
PAINT PINK (-7890 5250);
DISPLAY INVISIBLE (-7890 5250);
FORCEPROP 1 LAST Q_DEPT BU9
J 1
(-3763 49);
DISPLAY 1.957447 (-3763 49);
PAINT GREEN (-3763 49);
DISPLAY INVISIBLE (-3763 49);
FORCEPROP 1 LAST COMMENT_BODY TRUE
J 0
(12 -13);
DISPLAY 0.978723 (12 -13);
PAINT GREEN (12 -13);
DISPLAY INVISIBLE (12 -13);
WIRE 17 -1 (-5950 5475)(-5375 5475);
FORCEPROP 2 LAST SIG_NAME M_I_CPU0_SA_DQ<31:0>
J 0
(-5885 5485);
DISPLAY 0.489362 (-5885 5485);
WIRE 17 -1 (-7750 4075)(-7750 4100);
WIRE 17 -1 (-7750 4075)(-7750 4025);
WIRE 17 -1 (-7750 4100)(-8250 4100);
FORCEPROP 2 LAST SIG_NAME M_I_CPU0_SA_CB<7:0>
J 0
(-8200 4110);
DISPLAY 0.489362 (-8200 4110);
WIRE 17 -1 (-7750 3975)(-7750 3925);
WIRE 17 -1 (-7750 3975)(-7750 4025);
WIRE 17 -1 (-7750 3875)(-7750 3925);
WIRE 17 -1 (-7750 3825)(-7750 3875);
WIRE 17 -1 (-7750 3775)(-7750 3825);
WIRE 17 -1 (-7750 3725)(-7750 3775);
WIRE 17 -1 (-7750 3625)(-7750 3650);
WIRE 17 -1 (-7750 3625)(-7750 3575);
WIRE 17 -1 (-7750 3650)(-8250 3650);
FORCEPROP 2 LAST SIG_NAME M_I_CPU0_SB_CB<7:0>
J 0
(-8200 3660);
DISPLAY 0.489362 (-8200 3660);
WIRE 17 -1 (-7750 5175)(-7750 5225);
WIRE 17 -1 (-7750 5225)(-7750 5275);
WIRE 17 -1 (-7750 5275)(-7750 5325);
WIRE 17 -1 (-7750 5325)(-7750 5375);
WIRE 17 -1 (-7750 5375)(-7750 5425);
WIRE 17 -1 (-7750 5425)(-7750 5475);
WIRE 17 -1 (-7750 5475)(-7750 5500);
WIRE 17 -1 (-7750 5500)(-8250 5500);
FORCEPROP 2 LAST SIG_NAME M_I_CPU0_SA_CA<6:0>
J 0
(-8235 5510);
DISPLAY 0.489362 (-8235 5510);
WIRE 17 -1 (-7750 4775)(-7750 4825);
WIRE 17 -1 (-7750 4825)(-7750 4875);
WIRE 17 -1 (-7750 4875)(-7750 4925);
WIRE 17 -1 (-7750 4925)(-7750 4975);
WIRE 17 -1 (-7750 4975)(-7750 5025);
WIRE 17 -1 (-7750 5025)(-7750 5075);
WIRE 17 -1 (-7750 5075)(-7750 5100);
WIRE 17 -1 (-7750 5100)(-8250 5100);
FORCEPROP 2 LAST SIG_NAME M_I_CPU0_SB_CA<6:0>
J 0
(-8235 5110);
DISPLAY 0.489362 (-8235 5110);
WIRE 17 -1 (-7750 3525)(-7750 3575);
WIRE 17 -1 (-7750 3525)(-7750 3475);
WIRE 17 -1 (-7750 3425)(-7750 3475);
WIRE 17 -1 (-7750 3375)(-7750 3425);
WIRE 17 -1 (-7750 3325)(-7750 3375);
WIRE 17 -1 (-7750 3275)(-7750 3325);
WIRE 17 -1 (-5950 5475)(-5950 5425);
WIRE 17 -1 (-5950 5425)(-5950 5375);
WIRE 17 -1 (-5950 5375)(-5950 5325);
WIRE 17 -1 (-5950 5325)(-5950 5275);
WIRE 17 -1 (-5950 5275)(-5950 5225);
WIRE 17 -1 (-5950 5225)(-5950 5175);
WIRE 17 -1 (-5950 5175)(-5950 5125);
WIRE 17 -1 (-5950 5125)(-5950 5075);
WIRE 17 -1 (-5950 5075)(-5950 5025);
WIRE 17 -1 (-5950 5025)(-5950 4975);
WIRE 17 -1 (-5950 4975)(-5950 4925);
WIRE 17 -1 (-5950 4925)(-5950 4875);
WIRE 17 -1 (-5950 4875)(-5950 4825);
WIRE 17 -1 (-5950 4825)(-5950 4775);
WIRE 17 -1 (-5950 4775)(-5950 4725);
WIRE 17 -1 (-5950 4675)(-5950 4725);
WIRE 17 -1 (-5950 4625)(-5950 4675);
WIRE 17 -1 (-5950 4575)(-5950 4625);
WIRE 17 -1 (-5950 4525)(-5950 4575);
WIRE 17 -1 (-5950 4525)(-5950 4475);
WIRE 17 -1 (-5950 4475)(-5950 4425);
WIRE 17 -1 (-5950 4425)(-5950 4375);
WIRE 17 -1 (-5950 4375)(-5950 4325);
WIRE 17 -1 (-5950 4325)(-5950 4275);
WIRE 17 -1 (-5950 4275)(-5950 4225);
WIRE 17 -1 (-5950 4225)(-5950 4175);
WIRE 17 -1 (-5950 4175)(-5950 4125);
WIRE 17 -1 (-5950 4075)(-5950 4125);
WIRE 17 -1 (-5950 4025)(-5950 4075);
WIRE 17 -1 (-5950 3975)(-5950 4025);
WIRE 17 -1 (-5950 3925)(-5950 3975);
WIRE 17 -1 (-5950 3825)(-5375 3825);
FORCEPROP 2 LAST SIG_NAME M_I_CPU0_SB_DQ<31:0>
J 0
(-5885 3835);
DISPLAY 0.489362 (-5885 3835);
WIRE 17 -1 (-5950 3825)(-5950 3775);
WIRE 17 -1 (-5950 3775)(-5950 3725);
WIRE 17 -1 (-5950 3725)(-5950 3675);
WIRE 17 -1 (-5950 3675)(-5950 3625);
WIRE 17 -1 (-5950 3625)(-5950 3575);
WIRE 17 -1 (-5950 3575)(-5950 3525);
WIRE 17 -1 (-5950 3525)(-5950 3475);
WIRE 17 -1 (-5950 3475)(-5950 3425);
WIRE 17 -1 (-5950 3425)(-5950 3375);
WIRE 17 -1 (-5950 3375)(-5950 3325);
WIRE 17 -1 (-5950 3325)(-5950 3275);
WIRE 17 -1 (-5950 3275)(-5950 3225);
WIRE 17 -1 (-5950 3225)(-5950 3175);
WIRE 17 -1 (-5950 3175)(-5950 3125);
WIRE 17 -1 (-5950 3125)(-5950 3075);
WIRE 17 -1 (-5950 3025)(-5950 3075);
WIRE 17 -1 (-5950 2975)(-5950 3025);
WIRE 17 -1 (-5950 2925)(-5950 2975);
WIRE 17 -1 (-5950 2875)(-5950 2925);
WIRE 17 -1 (-5950 2875)(-5950 2825);
WIRE 17 -1 (-5950 2825)(-5950 2775);
WIRE 17 -1 (-5950 2775)(-5950 2725);
WIRE 17 -1 (-5950 2725)(-5950 2675);
WIRE 17 -1 (-5950 2675)(-5950 2625);
WIRE 17 -1 (-5950 2625)(-5950 2575);
WIRE 17 -1 (-5950 2575)(-5950 2525);
WIRE 17 -1 (-5950 2525)(-5950 2475);
WIRE 17 -1 (-5950 2425)(-5950 2475);
WIRE 17 -1 (-5950 2375)(-5950 2425);
WIRE 17 -1 (-5950 2325)(-5950 2375);
WIRE 17 -1 (-5950 2275)(-5950 2325);
WIRE 17 -1 (-3200 4375)(-3200 4275);
WIRE 17 -1 (-3200 4475)(-3200 4375);
WIRE 17 -1 (-3200 4275)(-3200 4175);
WIRE 17 -1 (-3200 4175)(-3200 4075);
WIRE 17 -1 (-3200 4500)(-3200 4475);
WIRE 17 -1 (-3200 4500)(-2500 4500);
FORCEPROP 2 LAST SIG_NAME M_I_CPU0_SA_DQS_DN<9:0>
J 0
(-3135 4510);
DISPLAY 0.489362 (-3135 4510);
WIRE 17 -1 (-3400 4325)(-3400 4225);
WIRE 17 -1 (-3400 4425)(-3400 4325);
WIRE 17 -1 (-3400 4225)(-3400 4125);
WIRE 17 -1 (-3400 4025)(-3400 4125);
WIRE 17 -1 (-3400 4525)(-3400 4425);
WIRE 17 -1 (-3400 4550)(-3400 4525);
WIRE 17 -1 (-3400 3925)(-3400 4025);
WIRE 17 -1 (-3400 3825)(-3400 3925);
WIRE 17 -1 (-3400 4550)(-2500 4550);
FORCEPROP 2 LAST SIG_NAME M_I_CPU0_SA_DQS_DP<9:0>
J 0
(-3135 4560);
DISPLAY 0.489362 (-3135 4560);
WIRE 17 -1 (-3400 3475)(-3400 3375);
WIRE 17 -1 (-3400 3500)(-3400 3475);
WIRE 17 -1 (-3400 3375)(-3400 3275);
WIRE 17 -1 (-3400 3275)(-3400 3175);
WIRE 17 -1 (-3400 3500)(-2500 3500);
FORCEPROP 2 LAST SIG_NAME M_I_CPU0_SB_DQS_DP<9:0>
J 0
(-3135 3510);
DISPLAY 0.489362 (-3135 3510);
WIRE 17 -1 (-3200 3425)(-3200 3325);
WIRE 17 -1 (-3200 3450)(-3200 3425);
WIRE 17 -1 (-3200 3325)(-3200 3225);
WIRE 17 -1 (-3200 3225)(-3200 3125);
WIRE 17 -1 (-3200 3450)(-2500 3450);
FORCEPROP 2 LAST SIG_NAME M_I_CPU0_SB_DQS_DN<9:0>
J 0
(-3135 3460);
DISPLAY 0.489362 (-3135 3460);
WIRE 17 -1 (-3400 3175)(-3400 3075);
WIRE 17 -1 (-3200 3675)(-3200 3575);
WIRE 17 -1 (-3200 3775)(-3200 3675);
WIRE 17 -1 (-3200 3775)(-3200 3875);
WIRE 17 -1 (-3200 3875)(-3200 3975);
WIRE 17 -1 (-3200 3975)(-3200 4075);
WIRE 17 -1 (-3400 3725)(-3400 3625);
WIRE 17 -1 (-3400 3825)(-3400 3725);
WIRE 17 -1 (-3200 2625)(-3200 2525);
WIRE 17 -1 (-3200 2725)(-3200 2625);
WIRE 17 -1 (-3200 2725)(-3200 2825);
WIRE 17 -1 (-3200 2825)(-3200 2925);
WIRE 17 -1 (-3200 2925)(-3200 3025);
WIRE 17 -1 (-3200 3125)(-3200 3025);
WIRE 17 -1 (-3400 2675)(-3400 2575);
WIRE 17 -1 (-3400 2775)(-3400 2675);
WIRE 17 -1 (-3400 2775)(-3400 2875);
WIRE 17 -1 (-3400 2875)(-3400 2975);
WIRE 17 -1 (-3400 2975)(-3400 3075);
WIRE 16 -1 (-8650 3100)(-8650 3175);
WIRE 16 -1 (-8350 2450)(-8350 2475);
WIRE 16 -1 (-7450 3250)(-7650 3250);
WIRE 16 -1 (-8550 3000)(-7450 3000);
WIRE 16 -1 (-8550 3400)(-8550 3000);
WIRE 16 -1 (-8550 3425)(-8550 3400);
WIRE 16 -1 (-8650 3400)(-8550 3400);
WIRE 16 -1 (-8650 3375)(-8650 3400);
WIRE 16 -1 (-8275 2900)(-8250 2900);
WIRE 16 -1 (-8275 2800)(-8275 2900);
WIRE 16 -1 (-8275 2800)(-8775 2800);
FORCEPROP 2 LAST SIG_NAME I3C_SPD_DDRGL_CPU0_SDA
J 0
(-8785 2810);
DISPLAY 0.489362 (-8785 2810);
WIRE 16 -1 (-8350 2250)(-8350 2200);
WIRE 16 -1 (-8150 2200)(-8350 2200);
WIRE 16 -1 (-8350 2200)(-8375 2200);
WIRE 16 -1 (-8150 2200)(-8150 2600);
WIRE 16 -1 (-7450 2600)(-8150 2600);
FORCEPROP 2 LAST SIG_NAME PWRGD_CHI_CPU0_DIMM
J 0
(-8050 2610);
DISPLAY 0.489362 (-8050 2610);
FORCEPROP 2 LASTPROP $XRERR UNIQUE?
J 0
(-8290 2610);
DISPLAY 0.638298 (-8290 2610);
PAINT MONO (-8290 2610);
DISPLAY INVISIBLE (-8290 2610);
WIRE 16 -1 (-7450 2900)(-8050 2900);
FORCEPROP 2 LAST SIG_NAME I3C_SPD_DDRI_CPU0_SDA
J 0
(-7960 2910);
DISPLAY 0.446809 (-7960 2910);
FORCEPROP 2 LASTPROP $XRERR UNIQUE?
J 0
(-8200 2910);
DISPLAY 0.638298 (-8200 2910);
PAINT MONO (-8200 2910);
DISPLAY INVISIBLE (-8200 2910);
WIRE 16 -1 (-7850 2675)(-8350 2675);
FORCEPROP 2 LAST SIG_NAME I3C_SPD_DDRGL_CPU0_SCL
J 0
(-8360 2685);
DISPLAY 0.489362 (-8360 2685);
WIRE 16 -1 (-7450 2950)(-8525 2950);
FORCEPROP 2 LAST SIG_NAME PD_CHI_CPU0_DIMM_SAA
J 0
(-8500 2960);
DISPLAY 0.489362 (-8500 2960);
WIRE 16 -1 (-7450 2850)(-7575 2850);
FORCEPROP 2 LAST SIG_NAME I3C_SPD_DDRI_CPU0_SCL
J 0
(-7960 2860);
DISPLAY 0.446809 (-7960 2860);
FORCEPROP 2 LASTPROP $XRERR UNIQUE?
J 0
(-8200 2860);
DISPLAY 0.638298 (-8200 2860);
PAINT MONO (-8200 2860);
DISPLAY INVISIBLE (-8200 2860);
WIRE 16 -1 (-7575 2850)(-7575 2675);
WIRE 16 -1 (-7575 2675)(-7650 2675);
WIRE 16 -1 (-7450 3150)(-8075 3150);
FORCEPROP 2 LAST SIG_NAME M_I_CPU0_RESET_N
J 0
(-8060 3160);
DISPLAY 0.489362 (-8060 3160);
WIRE 16 -1 (-7450 2050)(-8250 2050);
FORCEPROP 2 LAST SIG_NAME M_I_CPU0_SA_RSP<0>
J 0
(-8200 2060);
DISPLAY 0.489362 (-8200 2060);
WIRE 16 -1 (-7450 2000)(-8250 2000);
FORCEPROP 2 LAST SIG_NAME M_I_CPU0_SB_RSP<0>
J 0
(-8200 2010);
DISPLAY 0.489362 (-8200 2010);
WIRE 16 -1 (-6425 1475)(-6425 1400);
WIRE 16 -1 (-6425 1475)(-7150 1475);
FORCEPROP 2 LAST SIG_NAME PD_CHI_CPU0_DIMM_SAA
J 0
(-7135 1485);
DISPLAY 0.489362 (-7135 1485);
WIRE 16 -1 (-7450 3350)(-7650 3350);
WIRE 16 -1 (-7450 4150)(-8250 4150);
FORCEPROP 2 LAST SIG_NAME M_I_CPU0_CLK_DN<0>
J 0
(-8200 4160);
DISPLAY 0.489362 (-8200 4160);
WIRE 16 -1 (-7450 4000)(-7650 4000);
WIRE 16 -1 (-7450 3850)(-7650 3850);
WIRE 16 -1 (-7450 4950)(-7650 4950);
WIRE 16 -1 (-3650 3450)(-3500 3450);
WIRE 16 -1 (-3650 3400)(-3300 3400);
WIRE 16 -1 (-3650 4500)(-3500 4500);
WIRE 16 -1 (-3650 4450)(-3300 4450);
WIRE 16 -1 (-3500 4400)(-3650 4400);
WIRE 16 -1 (-3650 4350)(-3300 4350);
WIRE 16 -1 (-3650 3200)(-3300 3200);
WIRE 16 -1 (-3500 4300)(-3650 4300);
WIRE 16 -1 (-3500 3150)(-3650 3150);
WIRE 16 -1 (-3650 3100)(-3300 3100);
WIRE 16 -1 (-3650 4150)(-3300 4150);
WIRE 16 -1 (-3650 3050)(-3500 3050);
WIRE 16 -1 (-3650 3000)(-3300 3000);
WIRE 16 -1 (-3650 4100)(-3500 4100);
WIRE 16 -1 (-3650 4050)(-3300 4050);
WIRE 16 -1 (-3500 2950)(-3650 2950);
WIRE 16 -1 (-3650 2900)(-3300 2900);
WIRE 16 -1 (-3500 4000)(-3650 4000);
WIRE 16 -1 (-3650 3950)(-3300 3950);
WIRE 16 -1 (-3500 2850)(-3650 2850);
WIRE 16 -1 (-3650 2800)(-3300 2800);
WIRE 16 -1 (-3500 3900)(-3650 3900);
WIRE 16 -1 (-3650 3850)(-3300 3850);
WIRE 16 -1 (-3500 2750)(-3650 2750);
WIRE 16 -1 (-3650 2700)(-3300 2700);
WIRE 16 -1 (-3500 3800)(-3650 3800);
WIRE 16 -1 (-3650 3750)(-3300 3750);
WIRE 16 -1 (-3650 2650)(-3500 2650);
WIRE 16 -1 (-3650 2600)(-3300 2600);
WIRE 16 -1 (-3650 3700)(-3500 3700);
WIRE 16 -1 (-3650 3650)(-3300 3650);
WIRE 16 -1 (-3500 2550)(-3650 2550);
WIRE 16 -1 (-3650 2500)(-3300 2500);
WIRE 16 -1 (-3500 3600)(-3650 3600);
WIRE 16 -1 (-3650 3550)(-3300 3550);
WIRE 16 -1 (-3500 3250)(-3650 3250);
WIRE 16 -1 (-3650 3300)(-3300 3300);
WIRE 16 -1 (-3500 3350)(-3650 3350);
WIRE 16 -1 (-3500 4200)(-3650 4200);
WIRE 16 -1 (-3650 4250)(-3300 4250);
WIRE 16 -1 (-7450 4600)(-8250 4600);
FORCEPROP 2 LAST SIG_NAME M_I_CPU0_SB_PAR
J 0
(-8200 4610);
DISPLAY 0.489362 (-8200 4610);
WIRE 16 -1 (-7450 4650)(-8250 4650);
FORCEPROP 2 LAST SIG_NAME M_I_CPU0_SA_PAR
J 0
(-8200 4660);
DISPLAY 0.489362 (-8200 4660);
WIRE 16 -1 (-6050 2250)(-6250 2250);
WIRE 16 -1 (-6050 2300)(-6250 2300);
WIRE 16 -1 (-6050 2350)(-6250 2350);
WIRE 16 -1 (-6250 2400)(-6050 2400);
WIRE 16 -1 (-6050 2450)(-6250 2450);
WIRE 16 -1 (-6050 2500)(-6250 2500);
WIRE 16 -1 (-6050 2550)(-6250 2550);
WIRE 16 -1 (-6250 2600)(-6050 2600);
WIRE 16 -1 (-6050 2650)(-6250 2650);
WIRE 16 -1 (-6050 2700)(-6250 2700);
WIRE 16 -1 (-6050 2750)(-6250 2750);
WIRE 16 -1 (-6250 2800)(-6050 2800);
WIRE 16 -1 (-6050 2850)(-6250 2850);
WIRE 16 -1 (-6050 2900)(-6250 2900);
WIRE 16 -1 (-6050 2950)(-6250 2950);
WIRE 16 -1 (-6250 3000)(-6050 3000);
WIRE 16 -1 (-6050 3050)(-6250 3050);
WIRE 16 -1 (-6050 3100)(-6250 3100);
WIRE 16 -1 (-6050 3150)(-6250 3150);
WIRE 16 -1 (-6250 3200)(-6050 3200);
WIRE 16 -1 (-6050 3250)(-6250 3250);
WIRE 16 -1 (-6050 3300)(-6250 3300);
WIRE 16 -1 (-6050 3350)(-6250 3350);
WIRE 16 -1 (-6250 3400)(-6050 3400);
WIRE 16 -1 (-6050 3450)(-6250 3450);
WIRE 16 -1 (-6050 3500)(-6250 3500);
WIRE 16 -1 (-6050 3550)(-6250 3550);
WIRE 16 -1 (-6250 3600)(-6050 3600);
WIRE 16 -1 (-6050 3650)(-6250 3650);
WIRE 16 -1 (-6050 3700)(-6250 3700);
WIRE 16 -1 (-6050 3750)(-6250 3750);
WIRE 16 -1 (-6250 3800)(-6050 3800);
WIRE 16 -1 (-6050 3900)(-6250 3900);
WIRE 16 -1 (-6050 3950)(-6250 3950);
WIRE 16 -1 (-6050 4000)(-6250 4000);
WIRE 16 -1 (-6250 4050)(-6050 4050);
WIRE 16 -1 (-6050 4100)(-6250 4100);
WIRE 16 -1 (-6050 4150)(-6250 4150);
WIRE 16 -1 (-6050 4200)(-6250 4200);
WIRE 16 -1 (-6250 4250)(-6050 4250);
WIRE 16 -1 (-6050 4300)(-6250 4300);
WIRE 16 -1 (-6050 4350)(-6250 4350);
WIRE 16 -1 (-6050 4400)(-6250 4400);
WIRE 16 -1 (-6250 4450)(-6050 4450);
WIRE 16 -1 (-6050 4500)(-6250 4500);
WIRE 16 -1 (-6050 4550)(-6250 4550);
WIRE 16 -1 (-6050 4600)(-6250 4600);
WIRE 16 -1 (-6250 4650)(-6050 4650);
WIRE 16 -1 (-6050 4700)(-6250 4700);
WIRE 16 -1 (-6050 4750)(-6250 4750);
WIRE 16 -1 (-6050 4800)(-6250 4800);
WIRE 16 -1 (-6250 4850)(-6050 4850);
WIRE 16 -1 (-6050 4900)(-6250 4900);
WIRE 16 -1 (-6050 4950)(-6250 4950);
WIRE 16 -1 (-6050 5000)(-6250 5000);
WIRE 16 -1 (-6250 5050)(-6050 5050);
WIRE 16 -1 (-6050 5100)(-6250 5100);
WIRE 16 -1 (-6050 5150)(-6250 5150);
WIRE 16 -1 (-6050 5200)(-6250 5200);
WIRE 16 -1 (-6250 5250)(-6050 5250);
WIRE 16 -1 (-6050 5300)(-6250 5300);
WIRE 16 -1 (-6050 5350)(-6250 5350);
WIRE 16 -1 (-6050 5400)(-6250 5400);
WIRE 16 -1 (-7450 4350)(-8250 4350);
FORCEPROP 2 LAST SIG_NAME M_I_CPU0_SB_CS_N<1>
J 0
(-8200 4360);
DISPLAY 0.489362 (-8200 4360);
WIRE 16 -1 (-7450 4500)(-8250 4500);
FORCEPROP 2 LAST SIG_NAME M_I_CPU0_SA_CS_N<1>
J 0
(-8200 4510);
DISPLAY 0.489362 (-8200 4510);
WIRE 16 -1 (-7450 4300)(-8250 4300);
FORCEPROP 2 LAST SIG_NAME M_I_CPU0_SB_CS_N<0>
J 0
(-8200 4310);
DISPLAY 0.489362 (-8200 4310);
WIRE 16 -1 (-7450 4450)(-8250 4450);
FORCEPROP 2 LAST SIG_NAME M_I_CPU0_SA_CS_N<0>
J 0
(-8200 4460);
DISPLAY 0.489362 (-8200 4460);
WIRE 16 -1 (-7450 4200)(-8250 4200);
FORCEPROP 2 LAST SIG_NAME M_I_CPU0_CLK_DP<0>
J 0
(-8200 4210);
DISPLAY 0.489362 (-8200 4210);
WIRE 16 -1 (-7450 3300)(-7650 3300);
WIRE 16 -1 (-7450 3400)(-7650 3400);
WIRE 16 -1 (-7450 3450)(-7650 3450);
WIRE 16 -1 (-7450 3500)(-7650 3500);
WIRE 16 -1 (-7450 3550)(-7650 3550);
WIRE 16 -1 (-7450 3700)(-7650 3700);
WIRE 16 -1 (-7450 3800)(-7650 3800);
WIRE 16 -1 (-7450 3950)(-7650 3950);
WIRE 16 -1 (-7450 5050)(-7650 5050);
WIRE 16 -1 (-7450 5450)(-7650 5450);
WIRE 16 -1 (-7450 5000)(-7650 5000);
WIRE 16 -1 (-7450 5400)(-7650 5400);
WIRE 16 -1 (-7450 5350)(-7650 5350);
WIRE 16 -1 (-7450 4900)(-7650 4900);
WIRE 16 -1 (-7450 5300)(-7650 5300);
WIRE 16 -1 (-7450 4850)(-7650 4850);
WIRE 16 -1 (-7450 5250)(-7650 5250);
WIRE 16 -1 (-7450 4800)(-7650 4800);
WIRE 16 -1 (-7450 5200)(-7650 5200);
WIRE 16 -1 (-7450 4750)(-7650 4750);
WIRE 16 -1 (-7450 5150)(-7650 5150);
WIRE 16 -1 (-7450 3600)(-7650 3600);
WIRE 16 -1 (-7450 3750)(-7650 3750);
WIRE 16 -1 (-7450 3900)(-7650 3900);
WIRE 16 -1 (-7450 4050)(-7650 4050);
WIRE 16 -1 (-6250 5450)(-6050 5450);
WIRE 16 -1 (-8975 2200)(-8575 2200);
FORCEPROP 2 LAST SIG_NAME PWRGD_CHGL_CPU0
J 0
(-8960 2210);
DISPLAY 0.489362 (-8960 2210);
WIRE 16 -1 (-7450 3100)(-8075 3100);
FORCEPROP 2 LAST SIG_NAME M_I_CPU0_ALERT_N
J 0
(-8060 3110);
DISPLAY 0.489362 (-8060 3110);
WIRE 16 -1 (-1825 2250)(-2125 2250);
WIRE 16 -1 (-2125 2250)(-2125 2200);
WIRE 16 -1 (-2125 2300)(-2125 2250);
WIRE 16 -1 (-1825 2300)(-2125 2300);
WIRE 16 -1 (-2125 2350)(-2125 2300);
WIRE 16 -1 (-1825 2200)(-2125 2200);
WIRE 16 -1 (-2125 2200)(-2125 2075);
WIRE 16 -1 (-1825 2350)(-2125 2350);
WIRE 16 -1 (-2125 2400)(-2125 2350);
WIRE 16 -1 (-1825 2400)(-2125 2400);
WIRE 16 -1 (-2125 2450)(-2125 2400);
WIRE 16 -1 (-1825 2450)(-2125 2450);
WIRE 16 -1 (-2125 2500)(-2125 2450);
WIRE 16 -1 (-1825 2500)(-2125 2500);
WIRE 16 -1 (-2125 2550)(-2125 2500);
WIRE 16 -1 (-1825 2550)(-2125 2550);
WIRE 16 -1 (-2125 2600)(-2125 2550);
WIRE 16 -1 (-1825 2600)(-2125 2600);
WIRE 16 -1 (-2125 2650)(-2125 2600);
WIRE 16 -1 (-1825 2650)(-2125 2650);
WIRE 16 -1 (-2125 2700)(-2125 2650);
WIRE 16 -1 (-1825 2700)(-2125 2700);
WIRE 16 -1 (-2125 2750)(-2125 2700);
WIRE 16 -1 (-1825 2750)(-2125 2750);
WIRE 16 -1 (-2125 2800)(-2125 2750);
WIRE 16 -1 (-1825 2800)(-2125 2800);
WIRE 16 -1 (-2125 2850)(-2125 2800);
WIRE 16 -1 (-1825 2850)(-2125 2850);
WIRE 16 -1 (-2125 2900)(-2125 2850);
WIRE 16 -1 (-1825 2900)(-2125 2900);
WIRE 16 -1 (-2125 2950)(-2125 2900);
WIRE 16 -1 (-1825 2950)(-2125 2950);
WIRE 16 -1 (-2125 3000)(-2125 2950);
WIRE 16 -1 (-1825 3000)(-2125 3000);
WIRE 16 -1 (-2125 3050)(-2125 3000);
WIRE 16 -1 (-1825 3050)(-2125 3050);
WIRE 16 -1 (-2125 3100)(-2125 3050);
WIRE 16 -1 (-1825 3100)(-2125 3100);
WIRE 16 -1 (-2125 3150)(-2125 3100);
WIRE 16 -1 (-1825 3150)(-2125 3150);
WIRE 16 -1 (-2125 3200)(-2125 3150);
WIRE 16 -1 (-1825 3200)(-2125 3200);
WIRE 16 -1 (-2125 3250)(-2125 3200);
WIRE 16 -1 (-1825 3250)(-2125 3250);
WIRE 16 -1 (-2125 3300)(-2125 3250);
WIRE 16 -1 (-1825 3300)(-2125 3300);
WIRE 16 -1 (-2125 3350)(-2125 3300);
WIRE 16 -1 (-1825 3350)(-2125 3350);
WIRE 16 -1 (-2125 3400)(-2125 3350);
WIRE 16 -1 (-1825 3400)(-2125 3400);
WIRE 16 -1 (-2125 3450)(-2125 3400);
WIRE 16 -1 (-1825 3450)(-2125 3450);
WIRE 16 -1 (-2125 3500)(-2125 3450);
WIRE 16 -1 (-1825 3500)(-2125 3500);
WIRE 16 -1 (-2125 3550)(-2125 3500);
WIRE 16 -1 (-1825 3550)(-2125 3550);
WIRE 16 -1 (-2125 3600)(-2125 3550);
WIRE 16 -1 (-1825 3600)(-2125 3600);
WIRE 16 -1 (-2125 3650)(-2125 3600);
WIRE 16 -1 (-1825 3650)(-2125 3650);
WIRE 16 -1 (-2125 3700)(-2125 3650);
WIRE 16 -1 (-1825 3700)(-2125 3700);
WIRE 16 -1 (-2125 3750)(-2125 3700);
WIRE 16 -1 (-1825 3750)(-2125 3750);
WIRE 16 -1 (-2125 3800)(-2125 3750);
WIRE 16 -1 (-1825 3800)(-2125 3800);
WIRE 16 -1 (-2125 3850)(-2125 3800);
WIRE 16 -1 (-1825 3850)(-2125 3850);
WIRE 16 -1 (-2125 3900)(-2125 3850);
WIRE 16 -1 (-1825 3900)(-2125 3900);
WIRE 16 -1 (-2125 3950)(-2125 3900);
WIRE 16 -1 (-1825 3950)(-2125 3950);
WIRE 16 -1 (-2125 4000)(-2125 3950);
WIRE 16 -1 (-1825 4000)(-2125 4000);
WIRE 16 -1 (-2125 4050)(-2125 4000);
WIRE 16 -1 (-2125 4100)(-2125 4050);
WIRE 16 -1 (-1825 4050)(-2125 4050);
WIRE 16 -1 (-1825 4100)(-2125 4100);
WIRE 16 -1 (-2125 4150)(-2125 4100);
WIRE 16 -1 (-1825 4150)(-2125 4150);
WIRE 16 -1 (-2125 4200)(-2125 4150);
WIRE 16 -1 (-1825 4200)(-2125 4200);
WIRE 16 -1 (-2125 4250)(-2125 4200);
WIRE 16 -1 (-1825 4250)(-2125 4250);
WIRE 16 -1 (-2125 4300)(-2125 4250);
WIRE 16 -1 (-1825 4300)(-2125 4300);
WIRE 16 -1 (-2125 4350)(-2125 4300);
WIRE 16 -1 (-1825 4350)(-2125 4350);
WIRE 16 -1 (-2125 4400)(-2125 4350);
WIRE 16 -1 (-1825 4400)(-2125 4400);
WIRE 16 -1 (-2125 4450)(-2125 4400);
WIRE 16 -1 (-1825 4450)(-2125 4450);
WIRE 16 -1 (-2125 4500)(-2125 4450);
WIRE 16 -1 (-1825 4500)(-2125 4500);
WIRE 16 -1 (-2125 4550)(-2125 4500);
WIRE 16 -1 (-1825 4550)(-2125 4550);
WIRE 16 -1 (-2125 4600)(-2125 4550);
WIRE 16 -1 (-1825 4600)(-2125 4600);
WIRE 16 -1 (-2125 4650)(-2125 4600);
WIRE 16 -1 (-1825 4650)(-2125 4650);
WIRE 16 -1 (-2125 4700)(-2125 4650);
WIRE 16 -1 (-1825 4700)(-2125 4700);
WIRE 16 -1 (-2125 4750)(-2125 4700);
WIRE 16 -1 (-1825 4750)(-2125 4750);
WIRE 16 -1 (-2125 4800)(-2125 4750);
WIRE 16 -1 (-1825 4800)(-2125 4800);
WIRE 16 -1 (-2125 4850)(-2125 4800);
WIRE 16 -1 (-1825 4850)(-2125 4850);
WIRE 16 -1 (-2125 4900)(-2125 4850);
WIRE 16 -1 (-1825 4900)(-2125 4900);
WIRE 16 -1 (-2125 4950)(-2125 4900);
WIRE 16 -1 (-1825 4950)(-2125 4950);
WIRE 16 -1 (-2125 5000)(-2125 4950);
WIRE 16 -1 (-1825 5000)(-2125 5000);
WIRE 16 -1 (-2125 5050)(-2125 5000);
WIRE 16 -1 (-1825 5050)(-2125 5050);
WIRE 16 -1 (-2125 5100)(-2125 5050);
WIRE 16 -1 (-1825 5100)(-2125 5100);
WIRE 16 -1 (-2125 5150)(-2125 5100);
WIRE 16 -1 (-1825 5150)(-2125 5150);
WIRE 16 -1 (-2125 5200)(-2125 5150);
WIRE 16 -1 (-1825 5200)(-2125 5200);
WIRE 16 -1 (-2125 5250)(-2125 5200);
WIRE 16 -1 (-1825 5250)(-2125 5250);
WIRE 16 -1 (-2125 5300)(-2125 5250);
WIRE 16 -1 (-1825 5300)(-2125 5300);
WIRE 16 -1 (-325 2300)(-325 2200);
WIRE 16 -1 (-325 2350)(-325 2300);
WIRE 16 -1 (-325 2300)(-625 2300);
WIRE 16 -1 (-325 2200)(-325 2150);
WIRE 16 -1 (-325 2200)(-625 2200);
WIRE 16 -1 (-325 2150)(-325 2100);
WIRE 16 -1 (-325 2150)(-625 2150);
WIRE 16 -1 (-325 2400)(-325 2350);
WIRE 16 -1 (-325 2350)(-625 2350);
WIRE 16 -1 (-325 2450)(-325 2400);
WIRE 16 -1 (-325 2400)(-625 2400);
WIRE 16 -1 (-325 2100)(-625 2100);
WIRE 16 -1 (-325 2100)(-325 1850);
WIRE 16 -1 (-325 2500)(-325 2450);
WIRE 16 -1 (-325 2450)(-625 2450);
WIRE 16 -1 (-325 2550)(-325 2500);
WIRE 16 -1 (-325 2500)(-625 2500);
WIRE 16 -1 (-325 2600)(-325 2550);
WIRE 16 -1 (-325 2550)(-625 2550);
WIRE 16 -1 (-325 2650)(-325 2600);
WIRE 16 -1 (-325 2600)(-625 2600);
WIRE 16 -1 (-325 2700)(-325 2650);
WIRE 16 -1 (-325 2650)(-625 2650);
WIRE 16 -1 (-325 2750)(-325 2700);
WIRE 16 -1 (-325 2700)(-625 2700);
WIRE 16 -1 (-325 2800)(-325 2750);
WIRE 16 -1 (-325 2750)(-625 2750);
WIRE 16 -1 (-325 2850)(-325 2800);
WIRE 16 -1 (-325 2800)(-625 2800);
WIRE 16 -1 (-325 2900)(-325 2850);
WIRE 16 -1 (-325 2850)(-625 2850);
WIRE 16 -1 (-325 2950)(-325 2900);
WIRE 16 -1 (-325 2900)(-625 2900);
WIRE 16 -1 (-325 3000)(-325 2950);
WIRE 16 -1 (-325 2950)(-625 2950);
WIRE 16 -1 (-325 3050)(-325 3000);
WIRE 16 -1 (-325 3000)(-625 3000);
WIRE 16 -1 (-325 3100)(-325 3050);
WIRE 16 -1 (-325 3050)(-625 3050);
WIRE 16 -1 (-325 3150)(-325 3100);
WIRE 16 -1 (-325 3100)(-625 3100);
WIRE 16 -1 (-325 3200)(-325 3150);
WIRE 16 -1 (-325 3150)(-625 3150);
WIRE 16 -1 (-325 3250)(-325 3200);
WIRE 16 -1 (-325 3200)(-625 3200);
WIRE 16 -1 (-325 3300)(-325 3250);
WIRE 16 -1 (-325 3250)(-625 3250);
WIRE 16 -1 (-325 3350)(-325 3300);
WIRE 16 -1 (-325 3300)(-625 3300);
WIRE 16 -1 (-325 3400)(-325 3350);
WIRE 16 -1 (-325 3350)(-625 3350);
WIRE 16 -1 (-325 3450)(-325 3400);
WIRE 16 -1 (-325 3400)(-625 3400);
WIRE 16 -1 (-325 3500)(-325 3450);
WIRE 16 -1 (-325 3450)(-625 3450);
WIRE 16 -1 (-325 3550)(-325 3500);
WIRE 16 -1 (-325 3500)(-625 3500);
WIRE 16 -1 (-325 3600)(-325 3550);
WIRE 16 -1 (-325 3550)(-625 3550);
WIRE 16 -1 (-325 3650)(-325 3600);
WIRE 16 -1 (-325 3600)(-625 3600);
WIRE 16 -1 (-325 3700)(-325 3650);
WIRE 16 -1 (-325 3650)(-625 3650);
WIRE 16 -1 (-325 3750)(-325 3700);
WIRE 16 -1 (-325 3700)(-625 3700);
WIRE 16 -1 (-325 3800)(-325 3750);
WIRE 16 -1 (-325 3750)(-625 3750);
WIRE 16 -1 (-325 3850)(-325 3800);
WIRE 16 -1 (-325 3800)(-625 3800);
WIRE 16 -1 (-325 3900)(-325 3850);
WIRE 16 -1 (-325 3850)(-625 3850);
WIRE 16 -1 (-325 3950)(-325 3900);
WIRE 16 -1 (-325 3900)(-625 3900);
WIRE 16 -1 (-325 4000)(-325 3950);
WIRE 16 -1 (-325 3950)(-625 3950);
WIRE 16 -1 (-325 4050)(-325 4000);
WIRE 16 -1 (-325 4000)(-625 4000);
WIRE 16 -1 (-325 4100)(-325 4050);
WIRE 16 -1 (-325 4050)(-625 4050);
WIRE 16 -1 (-325 4150)(-325 4100);
WIRE 16 -1 (-325 4100)(-625 4100);
WIRE 16 -1 (-325 4200)(-325 4150);
WIRE 16 -1 (-325 4150)(-625 4150);
WIRE 16 -1 (-325 4250)(-325 4200);
WIRE 16 -1 (-325 4200)(-625 4200);
WIRE 16 -1 (-325 4300)(-325 4250);
WIRE 16 -1 (-325 4250)(-625 4250);
WIRE 16 -1 (-325 4350)(-325 4300);
WIRE 16 -1 (-325 4300)(-625 4300);
WIRE 16 -1 (-325 4400)(-325 4350);
WIRE 16 -1 (-325 4350)(-625 4350);
WIRE 16 -1 (-325 4450)(-325 4400);
WIRE 16 -1 (-325 4400)(-625 4400);
WIRE 16 -1 (-325 4500)(-325 4450);
WIRE 16 -1 (-325 4450)(-625 4450);
WIRE 16 -1 (-325 4550)(-325 4500);
WIRE 16 -1 (-325 4500)(-625 4500);
WIRE 16 -1 (-325 4600)(-325 4550);
WIRE 16 -1 (-325 4550)(-625 4550);
WIRE 16 -1 (-325 4650)(-325 4600);
WIRE 16 -1 (-325 4600)(-625 4600);
WIRE 16 -1 (-325 4700)(-325 4650);
WIRE 16 -1 (-325 4650)(-625 4650);
WIRE 16 -1 (-325 4750)(-325 4700);
WIRE 16 -1 (-325 4700)(-625 4700);
WIRE 16 -1 (-325 4800)(-325 4750);
WIRE 16 -1 (-325 4750)(-625 4750);
WIRE 16 -1 (-325 4850)(-325 4800);
WIRE 16 -1 (-325 4800)(-625 4800);
WIRE 16 -1 (-325 4900)(-325 4850);
WIRE 16 -1 (-325 4850)(-625 4850);
WIRE 16 -1 (-325 4950)(-325 4900);
WIRE 16 -1 (-325 4900)(-625 4900);
WIRE 16 -1 (-325 5000)(-325 4950);
WIRE 16 -1 (-325 4950)(-625 4950);
WIRE 16 -1 (-325 5050)(-325 5000);
WIRE 16 -1 (-325 5000)(-625 5000);
WIRE 16 -1 (-325 5100)(-325 5050);
WIRE 16 -1 (-325 5050)(-625 5050);
WIRE 16 -1 (-325 5150)(-325 5100);
WIRE 16 -1 (-325 5100)(-625 5100);
WIRE 16 -1 (-325 5200)(-325 5150);
WIRE 16 -1 (-325 5150)(-625 5150);
WIRE 16 -1 (-325 5250)(-325 5200);
WIRE 16 -1 (-325 5200)(-625 5200);
WIRE 16 -1 (-325 5300)(-325 5250);
WIRE 16 -1 (-325 5250)(-625 5250);
WIRE 16 -1 (-325 5350)(-325 5300);
WIRE 16 -1 (-325 5300)(-625 5300);
WIRE 16 -1 (-325 5400)(-325 5350);
WIRE 16 -1 (-325 5350)(-625 5350);
WIRE 16 -1 (-325 5450)(-325 5400);
WIRE 16 -1 (-325 5400)(-625 5400);
WIRE 16 -1 (-325 5450)(-625 5450);
WIRE 16 -1 (-2250 5675)(-2250 5800);
WIRE 16 -1 (-2250 5675)(-2825 5675);
WIRE 16 -1 (-2825 5675)(-2825 5800);
WIRE 16 -1 (-2825 5675)(-2825 5600);
WIRE 16 -1 (-2250 6100)(-2125 6100);
WIRE 16 -1 (-2250 6100)(-2250 6000);
WIRE 16 -1 (-2250 6100)(-2825 6100);
WIRE 16 -1 (-2125 5450)(-2125 6100);
WIRE 16 -1 (-1825 5450)(-2125 5450);
WIRE 16 -1 (-2125 5400)(-2125 5450);
WIRE 16 -1 (-2825 6000)(-2825 6100);
WIRE 16 -1 (-2825 6100)(-2825 6175);
WIRE 16 -1 (-1825 5400)(-2125 5400);
WIRE 16 -1 (-2125 5400)(-2125 5350);
WIRE 16 -1 (-2125 5350)(-1825 5350);
DOT 1 (-8350 2200);
DOT 1 (-8550 3400);
DOT 1 (-2125 2200);
DOT 1 (-2125 2250);
DOT 1 (-2125 2300);
DOT 1 (-2125 2350);
DOT 1 (-2125 2400);
DOT 1 (-2125 2450);
DOT 1 (-2125 2500);
DOT 1 (-2125 2550);
DOT 1 (-2125 2600);
DOT 1 (-2125 2650);
DOT 1 (-2125 2700);
DOT 1 (-2125 2750);
DOT 1 (-2125 2800);
DOT 1 (-2125 2900);
DOT 1 (-2125 2850);
DOT 1 (-2125 2950);
DOT 1 (-2125 3000);
DOT 1 (-2125 3050);
DOT 1 (-2125 3100);
DOT 1 (-2125 3150);
DOT 1 (-2125 3200);
DOT 1 (-2125 3250);
DOT 1 (-2125 3300);
DOT 1 (-2125 3350);
DOT 1 (-2125 3400);
DOT 1 (-2125 3450);
DOT 1 (-2125 3500);
DOT 1 (-2125 3550);
DOT 1 (-2125 3600);
DOT 1 (-2125 3650);
DOT 1 (-2125 3700);
DOT 1 (-2125 3750);
DOT 1 (-2125 3800);
DOT 1 (-2125 3850);
DOT 1 (-2125 3900);
DOT 1 (-2125 3950);
DOT 1 (-325 2100);
DOT 1 (-325 2150);
DOT 1 (-325 2200);
DOT 1 (-325 2300);
DOT 1 (-325 2400);
DOT 1 (-325 2350);
DOT 1 (-325 2450);
DOT 1 (-325 2500);
DOT 1 (-325 2550);
DOT 1 (-325 2600);
DOT 1 (-325 2650);
DOT 1 (-325 2700);
DOT 1 (-325 2750);
DOT 1 (-325 2800);
DOT 1 (-325 2900);
DOT 1 (-325 2850);
DOT 1 (-325 2950);
DOT 1 (-325 3000);
DOT 1 (-325 3050);
DOT 1 (-325 3100);
DOT 1 (-325 3150);
DOT 1 (-325 3200);
DOT 1 (-325 3250);
DOT 1 (-325 3300);
DOT 1 (-325 3350);
DOT 1 (-325 3400);
DOT 1 (-325 3450);
DOT 1 (-325 3500);
DOT 1 (-325 3550);
DOT 1 (-325 3600);
DOT 1 (-325 3650);
DOT 1 (-325 3700);
DOT 1 (-325 3750);
DOT 1 (-325 3800);
DOT 1 (-325 3850);
DOT 1 (-325 3900);
DOT 1 (-325 3950);
DOT 1 (-2125 4050);
DOT 1 (-2125 4000);
DOT 1 (-2125 4100);
DOT 1 (-2125 4150);
DOT 1 (-2125 4200);
DOT 1 (-2125 4250);
DOT 1 (-2125 4300);
DOT 1 (-2125 4350);
DOT 1 (-2125 4400);
DOT 1 (-2125 4450);
DOT 1 (-2125 4500);
DOT 1 (-2125 4550);
DOT 1 (-2125 4600);
DOT 1 (-2125 4650);
DOT 1 (-2125 4750);
DOT 1 (-2125 4800);
DOT 1 (-2125 4950);
DOT 1 (-2125 4900);
DOT 1 (-2125 5000);
DOT 1 (-2125 5100);
DOT 1 (-2125 5150);
DOT 1 (-2125 5200);
DOT 1 (-2125 5250);
DOT 1 (-2125 5400);
DOT 1 (-325 4000);
DOT 1 (-325 4050);
DOT 1 (-325 4100);
DOT 1 (-325 4150);
DOT 1 (-325 4200);
DOT 1 (-325 4250);
DOT 1 (-325 4300);
DOT 1 (-325 4350);
DOT 1 (-325 4400);
DOT 1 (-325 4450);
DOT 1 (-325 4500);
DOT 1 (-325 4550);
DOT 1 (-325 4600);
DOT 1 (-325 4650);
DOT 1 (-325 4700);
DOT 1 (-325 4750);
DOT 1 (-325 4800);
DOT 1 (-325 4850);
DOT 1 (-325 4950);
DOT 1 (-325 4900);
DOT 1 (-325 5000);
DOT 1 (-325 5050);
DOT 1 (-325 5100);
DOT 1 (-325 5150);
DOT 1 (-325 5200);
DOT 1 (-325 5250);
DOT 1 (-325 5300);
DOT 1 (-325 5350);
DOT 1 (-2825 5675);
DOT 1 (-2825 6100);
DOT 1 (-2250 6100);
DOT 1 (-2125 4700);
DOT 1 (-2125 5050);
DOT 1 (-2125 4850);
DOT 1 (-325 5400);
DOT 1 (-2125 5450);
QUIT
